G04 ================== begin FILE IDENTIFICATION RECORD ==================*
G04 Layout Name:  13948-1b.brd*
G04 Film Name:    DIF_REF_TOP*
G04 File Format:  Gerber RS274X*
G04 File Origin:  Cadence Allegro 16.5-S045*
G04 Origin Date:  Thu Nov 13 15:49:17 2014*
G04 *
G04 Layer:  BOARD GEOMETRY/OUTLINE*
G04 Layer:  BOARD GEOMETRY/DIF_REF_TOP*
G04 Layer:  BOARD GEOMETRY/PANEL_OUTLINE*
G04 *
G04 Offset:    (0.00 0.00)*
G04 Mirror:    No*
G04 Mode:      Positive*
G04 Rotation:  0*
G04 FullContactRelief:  No*
G04 UndefLineWidth:     6.00*
G04 ================== end FILE IDENTIFICATION RECORD ====================*
%FSLAX35Y35*MOIN*%
%IR0*IPPOS*OFA0.00000B0.00000*MIA0B0*SFA1.00000B1.00000*%
%ADD10C,.004*%
%ADD11C,.006*%
%ADD12C,.0035*%
%ADD13C,.0055*%
G75*
%LPD*%
G75*
G54D10*
G01X47245Y393623D02*
Y388351D01*
G01D02*
G03X47483Y387776I813J0D01*
G01X44095Y393623D02*
Y388281D01*
G01D02*
G02X43883Y387769I-724J0D01*
G01X45670Y403503D02*
Y409059D01*
G01D02*
G03X45083Y410476I-2004J0D01*
G01D02*
G02X44620Y411594I1118J1118D01*
G01D02*
Y436049D01*
G01X42520Y403503D02*
Y409758D01*
G01D02*
G02X42983Y410876I1581J0D01*
G01D02*
G03X43270Y411569I-693J693D01*
G01D02*
Y436049D01*
G01X44620D02*
G02X69453Y460882I24833J0D01*
G01X43270Y436049D02*
G02X69453Y462232I26183J0D01*
G01X66140Y393623D02*
Y388704D01*
G01D02*
G03X66483Y387876I1171J0D01*
G01X62990Y393623D02*
Y388276D01*
G01D02*
G02X62783Y387776I-707J0D01*
G01X56695Y393623D02*
Y388330D01*
G01D02*
G03X56883Y387876I642J0D01*
G01X53545Y393623D02*
Y388550D01*
G01D02*
G02X53183Y387676I-1236J0D01*
G01X61415Y403503D02*
Y408763D01*
G01D02*
G02X62069Y410342I2233J0D01*
G01D02*
G03X62315Y411254I-1564J911D01*
G01D02*
Y429930D01*
G01X64565Y403503D02*
Y408929D01*
G01D02*
G03X64088Y410081I-1629J0D01*
G01D02*
G02X63665Y411102I1021J1021D01*
G01D02*
Y429930D01*
G01X51970Y403503D02*
Y409238D01*
G01D02*
G02X52483Y410476I1751J0D01*
G01D02*
G03X52865Y411398I-922J922D01*
G01D02*
Y413083D01*
G01D02*
G03X52870Y413204I-1511J123D01*
G01D02*
Y436093D01*
G01X55120Y403503D02*
Y409121D01*
G01D02*
G03X54723Y410079I-1355J0D01*
G01D02*
G02X54220Y411618I2102J1539D01*
G01D02*
Y436093D01*
G01X62315Y429930D02*
G02X80617Y448232I18302J0D01*
G01X63665Y429930D02*
G02X80617Y446882I16952J0D01*
G01X52870Y436093D02*
G02X72009Y455232I19139J0D01*
G01X54220Y436093D02*
G02X72009Y453882I17789J0D01*
G01X72440Y393623D02*
Y389321D01*
G01D02*
G02X71883Y387976I-1902J0D01*
G01X75590Y393623D02*
Y389166D01*
G01D02*
G03X76083Y387976I1683J0D01*
G01X70865Y403503D02*
Y410025D01*
G01D02*
G02X71383Y411276I1769J0D01*
G01D02*
G03X71765Y412198I-922J922D01*
G01D02*
Y428497D01*
G01X74015Y403503D02*
Y409074D01*
G01D02*
G03X73683Y409876I-1134J0D01*
G01D02*
G02X73115Y411247I1371J1371D01*
G01D02*
Y428497D01*
G01X71765D02*
G02X84500Y441232I12735J0D01*
G01X73115Y428497D02*
G02X84500Y439882I11385J0D01*
G01X80617Y448232D02*
X103496D01*
G01X80617Y446882D02*
X103495D01*
G01X69453Y460882D02*
X110095D01*
G01X69453Y462232D02*
X110096D01*
G01X72009Y455232D02*
X106496D01*
G01X72009Y453882D02*
X106495D01*
G01X84500Y441232D02*
X99996D01*
G01D02*
G02X111557Y436443I0J-16350D01*
G01X84500Y439882D02*
X99995D01*
G01D02*
G02X110601Y435489I0J-15000D01*
G01X111557Y436443D02*
X276459Y271541D01*
G01X110601Y435489D02*
X275505Y270585D01*
G01X103496Y448232D02*
G02X115057Y443443I0J-16350D01*
G01D02*
X283209Y275291D01*
G01X103495Y446882D02*
G02X114101Y442489I0J-15000D01*
G01D02*
X282255Y274335D01*
G01X106495Y453882D02*
G02X117101Y449489I0J-15000D01*
G01X110095Y460882D02*
G02X120701Y456489I0J-15000D01*
G01X110096Y462232D02*
G02X121657Y457443I0J-16350D01*
G01X106496Y455232D02*
G02X118057Y450443I0J-16350D01*
G01X128874Y348209D02*
G03X138002Y326171I31166J-1D01*
G01X130224Y352709D02*
Y348209D01*
G01D02*
G03X138957Y327126I29816J0D01*
G01X128874Y352709D02*
Y348209D01*
G01X131147Y354709D02*
X130986Y354547D01*
G01D02*
G03X130224Y352709I1838J-1839D01*
G01X127301Y354709D02*
X128572Y353438D01*
G01D02*
G02X128874Y352709I-729J-729D01*
G01X117101Y449489D02*
X290315Y276275D01*
G01X120701Y456489D02*
X298115Y279075D01*
G01X121657Y457443D02*
X299069Y280031D01*
G01X118057Y450443D02*
X291269Y277231D01*
G01X142374Y323709D02*
X147252Y318830D01*
G01D02*
G03X152374Y316709I5121J5122D01*
G01X141419Y322754D02*
X146297Y317875D01*
G01D02*
G03X152375Y315359I6076J6077D01*
G01X140524Y342279D02*
G03X145919Y329254I18421J0D01*
G01D02*
X149005Y326168D01*
G01D02*
G03X153375Y324359I4368J4369D01*
G01X141874Y342280D02*
G03X146874Y330209I17071J0D01*
G01D02*
X149960Y327123D01*
G01X138957Y327126D02*
X142374Y323709D01*
G01X138002Y326171D02*
X141419Y322754D01*
G01X140524Y352509D02*
Y342279D01*
G01X141874Y352509D02*
Y342280D01*
G01X139301Y354709D02*
X139833Y354177D01*
G01D02*
G02X140524Y352509I-1668J-1668D01*
G01X143147Y354709D02*
X142529Y354092D01*
G01D02*
G03X141874Y352509I1583J-1582D01*
G01X166924Y295440D02*
X165793Y294309D01*
G01X164567Y313347D02*
Y317397D01*
G01D02*
G02X164967Y317797I400J0D01*
G01D02*
X165066D01*
G01D02*
G03X165466Y318197I0J400D01*
G01D02*
Y326709D01*
G01X152374Y316709D02*
X154374D01*
G01D02*
G03X155061Y316993I1J971D01*
G01D02*
X155874Y317807D01*
G01X152375Y315359D02*
X154476D01*
G01D02*
X155874Y313961D01*
G01X165466Y326709D02*
G03X164992Y327855I-1620J1D01*
G01D02*
X164147Y328699D01*
G01X167374Y331709D02*
G02X152374Y346709I0J15000D01*
G01X153724D02*
G03X167374Y333059I13650J0D01*
G01X153375Y324359D02*
X154626D01*
G01D02*
X155874Y323111D01*
G01X149960Y327123D02*
G03X153374Y325709I3414J3414D01*
G01D02*
X154626D01*
G01D02*
X155874Y326957D01*
G01X164049Y353037D02*
Y351709D01*
G01D02*
G03X172899Y342859I8850J0D01*
G01X165399Y353685D02*
Y351709D01*
G01D02*
G03X172899Y344209I7500J0D01*
G01X152374Y346709D02*
Y352809D01*
G01X153724Y353936D02*
Y346709D01*
G01X162801Y354709D02*
X163749Y353761D01*
G01D02*
G02X164049Y353037I-724J-724D01*
G01X166423Y354709D02*
G03X165699Y354409I0J-1024D01*
G01D02*
G03X165399Y353685I724J-724D01*
G01X152374Y352809D02*
G03X151789Y354221I-1997J0D01*
G01D02*
X151301Y354709D01*
G01X155147D02*
X154663D01*
G01D02*
G03X153999Y354434I0J-939D01*
G01D02*
X153882Y354317D01*
G01D02*
G03X153724Y353936I380J-381D01*
G01X175590Y303465D02*
Y299415D01*
G01D02*
G03X175990Y299015I400J0D01*
G01D02*
X176090D01*
G01D02*
G02X176490Y298615I0J-400D01*
G01D02*
Y296323D01*
G01D02*
G02X176373Y296040I-401J0D01*
G01D02*
X175242Y294909D01*
G01X178740Y303465D02*
Y299415D01*
G01D02*
G02X178340Y299015I-400J0D01*
G01D02*
X178240D01*
G01D02*
G03X177840Y298615I0J-400D01*
G01D02*
Y296323D01*
G01D02*
G03X177957Y296040I401J0D01*
G01D02*
X179088Y294909D01*
G01X169291Y303465D02*
Y299415D01*
G01D02*
G02X168891Y299015I-400J0D01*
G01D02*
X168791D01*
G01D02*
G03X168391Y298615I0J-400D01*
G01D02*
Y295723D01*
G01D02*
G03X168508Y295440I401J0D01*
G01D02*
X169639Y294309D01*
G01X166141Y303465D02*
Y299415D01*
G01D02*
G03X166541Y299015I400J0D01*
G01D02*
X166641D01*
G01D02*
G02X167041Y298615I0J-400D01*
G01D02*
Y295723D01*
G01D02*
G02X166924Y295440I-401J0D01*
G01X167716Y313347D02*
Y317397D01*
G01D02*
G03X167316Y317797I-400J0D01*
G01D02*
X167216D01*
G01D02*
G02X166816Y318197I0J400D01*
G01D02*
Y326709D01*
G01X177165Y313347D02*
Y317397D01*
G01D02*
G03X176765Y317797I-400J0D01*
G01D02*
X176665D01*
G01D02*
G02X176265Y318197I0J400D01*
G01D02*
Y320209D01*
G01X174015Y313347D02*
Y317397D01*
G01D02*
G02X174415Y317797I400J0D01*
G01D02*
X174515D01*
G01D02*
G03X174915Y318197I0J400D01*
G01D02*
Y320210D01*
G01X166816Y326709D02*
G02X167391Y328097I1963J0D01*
G01D02*
X167993Y328699D01*
G01X176265Y320209D02*
G02X177249Y322583I3358J-1D01*
G01D02*
G03X178374Y325299I-2716J2716D01*
G01D02*
Y326709D01*
G01D02*
G02X178934Y328061I1912J0D01*
G01D02*
X179622Y328749D01*
G01X174915Y320210D02*
G02X176294Y323538I4708J-1D01*
G01D02*
G03X177024Y325298I-1761J1762D01*
G01D02*
Y326709D01*
G01D02*
G03X176464Y328061I-1912J0D01*
G01D02*
X175776Y328749D01*
G01X189874Y331709D02*
X167374D01*
G01Y333059D02*
X189874D01*
G01X172899Y342859D02*
X189874D01*
G01X172899Y344209D02*
X189874D01*
G01X166647Y354709D02*
X166423D01*
G01X192874Y330461D02*
X192865Y330470D01*
G01D02*
G03X189874Y331709I-2991J-2991D01*
G01Y333059D02*
G03X192865Y334298I0J4230D01*
G01D02*
X192874Y334307D01*
G01X189874Y342859D02*
G02X192865Y341620I0J-4230D01*
G01D02*
X192874Y341611D01*
G01X189874Y344209D02*
G03X192865Y345448I0J4230D01*
G01D02*
X192874Y345457D01*
G01X210236Y303465D02*
Y299415D01*
G01D02*
G03X210636Y299015I400J0D01*
G01D02*
X210735D01*
G01D02*
G02X211135Y298615I0J-400D01*
G01D02*
Y296323D01*
G01D02*
G02X211018Y296040I-401J0D01*
G01D02*
X209887Y294909D01*
G01X213385Y303465D02*
Y299415D01*
G01D02*
G02X212985Y299015I-400J0D01*
G01D02*
X212885D01*
G01D02*
G03X212485Y298615I0J-400D01*
G01D02*
Y296323D01*
G01D02*
G03X212602Y296040I401J0D01*
G01D02*
X213733Y294909D01*
G01X200787Y303465D02*
Y299415D01*
G01D02*
G03X201187Y299015I400J0D01*
G01D02*
X201287D01*
G01D02*
G02X201687Y298615I0J-400D01*
G01D02*
Y296323D01*
G01D02*
G02X201570Y296040I-401J0D01*
G01D02*
X200439Y294909D01*
G01X203937Y303465D02*
Y299415D01*
G01D02*
G02X203537Y299015I-400J0D01*
G01D02*
X203437D01*
G01D02*
G03X203037Y298615I0J-400D01*
G01D02*
Y296323D01*
G01D02*
G03X203154Y296040I401J0D01*
G01D02*
X204285Y294909D01*
G01X208661Y313347D02*
Y317397D01*
G01D02*
G02X209061Y317797I400J0D01*
G01D02*
X209161D01*
G01D02*
G03X209561Y318197I0J400D01*
G01D02*
Y321908D01*
G01X211811Y313347D02*
Y317397D01*
G01D02*
G03X211411Y317797I-400J0D01*
G01D02*
X211311D01*
G01D02*
G02X210911Y318197I0J400D01*
G01D02*
Y321908D01*
G01X202362Y313347D02*
Y317397D01*
G01D02*
G03X201962Y317797I-400J0D01*
G01D02*
X201862D01*
G01D02*
G02X201462Y318197I0J400D01*
G01D02*
Y321883D01*
G01X199212Y313347D02*
Y317397D01*
G01D02*
G02X199612Y317797I400J0D01*
G01D02*
X199712D01*
G01D02*
G03X200112Y318197I0J400D01*
G01D02*
Y321883D01*
G01X209561Y321908D02*
G03X209444Y322191I-401J0D01*
G01D02*
X208338Y323297D01*
G01X210911Y321908D02*
G02X211028Y322191I401J0D01*
G01D02*
X212134Y323297D01*
G01X201462Y321883D02*
G02X201579Y322166I401J0D01*
G01D02*
X202710Y323297D01*
G01X200112Y321883D02*
G03X199995Y322166I-401J0D01*
G01D02*
X198864Y323297D01*
G01X278510Y204925D02*
X308858Y174577D01*
G01X276969Y205385D02*
G03X277555Y203970I2001J0D01*
G01D02*
X324177Y157348D01*
G01X278319Y267051D02*
Y205385D01*
G01D02*
G03X278510Y204925I651J1D01*
G01X276969Y267050D02*
Y205385D01*
G01X276459Y271541D02*
G02X278319Y267051I-4490J-4490D01*
G01X275505Y270585D02*
G02X276969Y267050I-3536J-3535D01*
G01X279528Y1008860D02*
Y1001110D01*
G01D02*
G03X279928Y1000710I400J0D01*
G01D02*
X280421D01*
G01D02*
G02X280821Y1000310I0J-400D01*
G01X286158Y208230D02*
X329458Y164930D01*
G01X285203Y207275D02*
X328503Y163975D01*
G01X285069Y270801D02*
Y220023D01*
G01D02*
G03X285539Y219083I1140J-18D01*
G01D02*
G02X286009Y218143I-670J-922D01*
G01D02*
Y216943D01*
G01D02*
G02X285539Y216003I-1140J-18D01*
G01D02*
G03X285069Y215063I670J-922D01*
G01D02*
Y210859D01*
G01D02*
G03X286158Y208230I3718J0D01*
G01X283719Y270800D02*
Y210858D01*
G01D02*
G03X285203Y207275I5068J0D01*
G01X293129Y221353D02*
Y211800D01*
G01D02*
G03X293832Y210103I2400J0D01*
G01D02*
X332175Y171760D01*
G01X291779Y272740D02*
Y211799D01*
G01D02*
G03X292877Y209148I3750J0D01*
G01D02*
X331220Y170805D01*
G01X293129Y272741D02*
Y232473D01*
G01D02*
G03X293599Y231533I1140J-18D01*
G01D02*
G02X294069Y230593I-670J-922D01*
G01D02*
Y229393D01*
G01D02*
G02X293599Y228453I-1140J-18D01*
G01D02*
G03X293129Y227513I670J-922D01*
G01D02*
Y226313D01*
G01D02*
G03Y226251I1140J-31D01*
G01D02*
G03X293599Y225373I1139J45D01*
G01D02*
G02X294069Y224433I-670J-922D01*
G01D02*
Y223233D01*
G01D02*
G02X293599Y222293I-1140J-18D01*
G01D02*
G03X293129Y221353I670J-922D01*
G01X283209Y275291D02*
G02X285069Y270801I-4490J-4490D01*
G01X282255Y274335D02*
G02X283719Y270800I-3536J-3535D01*
G01X291269Y277231D02*
G02X293129Y272741I-4490J-4490D01*
G01X290315Y276275D02*
G02X291779Y272740I-3536J-3535D01*
G01X289410Y954200D02*
Y761421D01*
G01D02*
G03X293441Y751689I13764J0D01*
G01D02*
X398925Y646205D01*
G01X290760Y954201D02*
Y761422D01*
G01D02*
G03X294396Y752644I12414J0D01*
G01D02*
X324516Y722524D01*
G01X296728Y763527D02*
G03X299507Y756818I9488J0D01*
G01X296728Y999200D02*
Y763527D01*
G01X285435Y963796D02*
G02X289410Y954200I-9595J-9596D01*
G01X286390Y964751D02*
G02X290760Y954201I-10550J-10550D01*
G01X280821Y1000310D02*
Y971872D01*
G01D02*
G03X283268Y965963I8356J-1D01*
G01D02*
X285435Y963796D01*
G01X282171Y1000310D02*
Y971872D01*
G01D02*
G03X284223Y966918I7006J0D01*
G01D02*
X286390Y964751D01*
G01X283463Y1008860D02*
Y1001110D01*
G01D02*
G02X283063Y1000710I-400J0D01*
G01D02*
X282571D01*
G01D02*
G03X282171Y1000310I0J-400D01*
G01X295273Y1008860D02*
Y1002714D01*
G01D02*
G03X295986Y1000993I2434J0D01*
G01D02*
G02X296728Y999200I-1793J-1792D01*
G01X312033Y172067D02*
G03X312365Y171070I1126J-179D01*
G01D02*
X325132Y158303D01*
G01X308858Y174577D02*
G03X309855Y174245I818J794D01*
G01D02*
G02X310852Y173913I179J-1126D01*
G01D02*
X311700Y173064D01*
G01D02*
G02X312033Y172067I-793J-819D01*
G01X300979Y210751D02*
X334246Y177484D01*
G01X309825Y204480D02*
G03X310157Y203483I1126J-179D01*
G01D02*
X311005Y202635D01*
G01D02*
G03X312002Y202302I819J793D01*
G01D02*
G02X312999Y201970I179J-1126D01*
G01D02*
X313848Y201121D01*
G01X299579Y275540D02*
Y214131D01*
G01D02*
G03X300979Y210751I4781J0D01*
G01X300929Y275541D02*
Y214132D01*
G01D02*
G03X301934Y211706I3431J0D01*
G01D02*
X306650Y206990D01*
G01D02*
G03X307647Y206658I818J794D01*
G01D02*
G02X308644Y206326I179J-1126D01*
G01D02*
X309492Y205477D01*
G01D02*
G02X309825Y204480I-793J-819D01*
G01X298115Y279075D02*
G02X299579Y275540I-3536J-3535D01*
G01X299069Y280031D02*
G02X300929Y275541I-4490J-4490D01*
G01X299507Y756818D02*
X406085Y650240D01*
G01X298078Y763528D02*
G03X300462Y757773I8138J0D01*
G01D02*
X310926Y747309D01*
G01D02*
G03X311923Y746976I819J793D01*
G01D02*
G02X312920Y746644I179J-1126D01*
G01D02*
X313769Y745795D01*
G01X304000Y766995D02*
G03X306565Y760801I8759J-1D01*
G01D02*
X413619Y653747D01*
G01X305350Y766995D02*
G03X307520Y761756I7409J0D01*
G01D02*
X322246Y747030D01*
G01X298078Y999597D02*
Y763528D01*
G01X304000Y979166D02*
Y766995D01*
G01X305350Y979166D02*
Y766995D01*
G01X311000Y971673D02*
Y770194D01*
G01D02*
G03X312813Y765817I6191J0D01*
G01D02*
X419408Y659222D01*
G01X312350Y971673D02*
Y770195D01*
G01D02*
G03X313768Y766772I4841J0D01*
G01X313705Y978205D02*
G03X311000Y971673I6532J-6531D01*
G01X314660Y977250D02*
G03X312350Y971673I5577J-5577D01*
G01X312329Y993208D02*
G02X310292Y988291I-6953J0D01*
G01D02*
X306002Y984001D01*
G01D02*
G03X304000Y979166I4835J-4834D01*
G01X313679Y993207D02*
G02X311247Y987336I-8303J0D01*
G01D02*
X306957Y983046D01*
G01D02*
G03X305350Y979166I3880J-3880D01*
G01X299213Y1008860D02*
Y1002337D01*
G01D02*
G02X298646Y1000968I-1936J0D01*
G01D02*
G03X298078Y999597I1371J-1371D01*
G01X311023Y1008860D02*
Y1003947D01*
G01D02*
G03X311213Y1002990I2500J-1D01*
G01D02*
X312138Y1000759D01*
G01D02*
G02X312328Y999803I-2310J-956D01*
G01D02*
Y993631D01*
G01D02*
X312329D01*
G01D02*
Y993208D01*
G01X337215Y138425D02*
X328759D01*
G01D02*
G02X328453Y138486I0J800D01*
G01D02*
X327594Y138841D01*
G01X337215Y137075D02*
X328986D01*
G01D02*
G03X327100Y136294I0J-2667D01*
G01X337416Y143575D02*
X324013D01*
G01D02*
G02X323138Y143938I0J1237D01*
G01D02*
X322775Y144300D01*
G01D02*
X321214D01*
G01D02*
G03X320931Y144183I0J-401D01*
G01D02*
X319800Y143052D01*
G01X337416Y144925D02*
X324226D01*
G01D02*
G02X323944Y145042I1J400D01*
G01D02*
X323451Y145533D01*
G01D02*
G03X323169Y145650I-283J-283D01*
G01D02*
X321214D01*
G01D02*
G02X320931Y145767I0J401D01*
G01D02*
X319800Y146898D01*
G01X327594Y138841D02*
G02X327100Y139581I306J739D01*
G01D02*
Y139857D01*
G01X329458Y164930D02*
G03X331220Y164200I1762J1762D01*
G01X328503Y163975D02*
G03X331219Y162850I2716J2717D01*
G01X325132Y158303D02*
G03X325864Y158000I732J732D01*
G01D02*
X328158D01*
G01D02*
G03X329098Y158470I18J1140D01*
G01D02*
G02X330038Y158940I922J-670D01*
G01X324177Y157348D02*
G03X325864Y156650I1686J1687D01*
G01D02*
X337871D01*
G01X318868Y194772D02*
X335201Y178439D01*
G01X313848Y201121D02*
G02X314180Y200124I-794J-818D01*
G01D02*
G03X314513Y199127I1126J-178D01*
G01D02*
X315361Y198279D01*
G01D02*
G03X316358Y197946I819J793D01*
G01D02*
G02X317355Y197614I179J-1126D01*
G01D02*
X318204Y196766D01*
G01D02*
G02X318536Y195769I-794J-818D01*
G01D02*
G03X318868Y194772I1126J-179D01*
G01X324516Y722524D02*
G03X325513Y722192I818J794D01*
G01D02*
G02X326510Y721860I179J-1126D01*
G01D02*
X327358Y721011D01*
G01D02*
G02X327691Y720014I-793J-819D01*
G01D02*
G03X328023Y719017I1126J-179D01*
G01D02*
X328872Y718168D01*
G01D02*
G03X329869Y717836I818J794D01*
G01D02*
G02X330866Y717504I179J-1126D01*
G01X323145Y735090D02*
X352203Y706032D01*
G01X313769Y745795D02*
G02X314101Y744798I-794J-818D01*
G01D02*
G03X314434Y743801I1126J-178D01*
G01D02*
X315282Y742953D01*
G01D02*
G03X316279Y742621I818J794D01*
G01D02*
G02X317276Y742288I178J-1126D01*
G01D02*
X318125Y741440D01*
G01D02*
G02X318457Y740443I-794J-818D01*
G01D02*
G03X318789Y739446I1126J-179D01*
G01D02*
X319638Y738597D01*
G01D02*
G03X320635Y738265I818J794D01*
G01D02*
G02X321632Y737932I178J-1126D01*
G01D02*
X322480Y737084D01*
G01D02*
G02X322813Y736087I-793J-819D01*
G01D02*
G03X323145Y735090I1126J-179D01*
G01X324240Y746366D02*
X325088Y745517D01*
G01D02*
G02X325421Y744520I-793J-819D01*
G01D02*
G03X325753Y743523I1126J-179D01*
G01D02*
X326602Y742674D01*
G01D02*
G03X327599Y742342I818J794D01*
G01D02*
G02X328596Y742010I179J-1126D01*
G01D02*
X329444Y741161D01*
G01D02*
G02X329776Y740164I-794J-818D01*
G01D02*
G03X330109Y739167I1126J-178D01*
G01X322246Y747030D02*
G03X323243Y746698I818J794D01*
G01D02*
G02X324240Y746366I179J-1126D01*
G01X313768Y766772D02*
X318886Y761654D01*
G01D02*
G03X319883Y761322I818J794D01*
G01D02*
G02X320880Y760989I178J-1126D01*
G01D02*
X321729Y760141D01*
G01D02*
G02X322061Y759144I-794J-818D01*
G01D02*
G03X322393Y758147I1126J-179D01*
G01D02*
X323242Y757298D01*
G01D02*
G03X324239Y756966I818J794D01*
G01D02*
G02X325236Y756633I178J-1126D01*
G01D02*
X326084Y755785D01*
G01D02*
G02X326417Y754788I-793J-819D01*
G01D02*
G03X326749Y753791I1126J-179D01*
G01D02*
X327598Y752942D01*
G01D02*
G03X328595Y752610I818J794D01*
G01D02*
G02X329592Y752278I179J-1126D01*
G01D02*
X330440Y751429D01*
G01X322038Y767826D02*
X427021Y662843D01*
G01X322995Y768779D02*
X334589Y757185D01*
G01X318000Y961800D02*
Y777214D01*
G01D02*
G03X321782Y768083I12916J1D01*
G01D02*
X322038Y767826D01*
G01X319350Y961799D02*
Y777215D01*
G01D02*
G03X322738Y769037I11566J1D01*
G01D02*
X322995Y768779D01*
G01X325000Y780578D02*
G03X328417Y772327I11668J-1D01*
G01D02*
X434717Y666027D01*
G01X326350Y780578D02*
G03X329372Y773282I10318J0D01*
G01D02*
X358005Y744649D01*
G01X325000Y958512D02*
Y780578D01*
G01X326350Y958513D02*
Y780578D01*
G01X327419Y964352D02*
G03X325000Y958512I5840J-5840D01*
G01X328374Y963397D02*
G03X326350Y958513I4885J-4886D01*
G01X342256Y990310D02*
X321008Y969062D01*
G01D02*
G03X318000Y961800I7263J-7262D01*
G01X343211Y989355D02*
X321963Y968107D01*
G01D02*
G03X319350Y961799I6308J-6308D01*
G01X330941Y965811D02*
G03X327419Y964352I0J-4981D01*
G01X330942Y964461D02*
G03X328374Y963397I0J-3631D01*
G01X328066Y994314D02*
G02X326829Y991329I-4222J1D01*
G01D02*
X313705Y978205D01*
G01X329416Y994314D02*
G02X327784Y990374I-5572J0D01*
G01D02*
X314660Y977250D01*
G01X314958Y1008860D02*
Y1002667D01*
G01D02*
G02X314444Y1001426I-1755J0D01*
G01D02*
G03X313678Y999577I1849J-1849D01*
G01D02*
Y994500D01*
G01D02*
X313679D01*
G01D02*
Y993207D01*
G01X326773Y1008860D02*
Y1001110D01*
G01D02*
G03X327173Y1000710I400J0D01*
G01D02*
X327666D01*
G01D02*
G02X328066Y1000310I0J-400D01*
G01D02*
Y994314D01*
G01X330308Y1000710D02*
X329816D01*
G01D02*
G03X329416Y1000310I0J-400D01*
G01D02*
Y994314D01*
G01X341640Y130000D02*
X341918Y130278D01*
G01D02*
G02X342300Y130483I534J-537D01*
G01D02*
X342301Y130484D01*
G01D02*
G02X342315Y130486I114J-748D01*
G01D02*
G02X342451Y130499I140J-744D01*
G01D02*
G02X342454Y130500I241J-718D01*
G01D02*
X344640D01*
G01D02*
G03X346056Y131086I1J2002D01*
G01D02*
X350399Y135429D01*
G01X339440Y130000D02*
X338323D01*
G01D02*
G02X338040Y130117I0J401D01*
G01D02*
X337699Y130458D01*
G01D02*
G03X337416Y130575I-283J-284D01*
G01D02*
X337260D01*
G01D02*
X337259Y130574D01*
G01D02*
X335872D01*
G01D02*
G03X335589Y130457I0J-401D01*
G01D02*
X334600Y129468D01*
G01X339440Y132500D02*
X338323D01*
G01D02*
G03X338040Y132383I0J-401D01*
G01D02*
X337699Y132042D01*
G01D02*
G02X337416Y131925I-283J284D01*
G01D02*
X336700D01*
G01D02*
X336699Y131924D01*
G01D02*
X335873D01*
G01D02*
G02X335590Y132041I0J401D01*
G01D02*
X334600Y133031D01*
G01X341640Y132500D02*
G03X343209Y131850I1569J1569D01*
G01D02*
X344640D01*
G01D02*
G03X345101Y132041I0J652D01*
G01D02*
X349444Y136384D01*
G01X341640Y139000D02*
G03X343241Y138337I1601J1601D01*
G01D02*
X343807D01*
G01D02*
X343985Y138382D01*
G01D02*
X343987Y138383D01*
G01D02*
X344081Y138454D01*
G01D02*
X344083Y138456D01*
G01D02*
G03X344096Y138468I-332J373D01*
G01D02*
X344590Y138961D01*
G01X337897Y138740D02*
X337842Y138685D01*
G01D02*
G02X337215Y138425I-627J626D01*
G01X339440Y136500D02*
X338524D01*
G01D02*
G02X337897Y136760I0J886D01*
G01D02*
X337842Y136815D01*
G01D02*
G03X337215Y137075I-627J-626D01*
G01X341640Y136500D02*
X342990D01*
G01D02*
G03X344259Y136876I-1J2332D01*
G01D02*
G03X344639Y137183I-1267J1957D01*
G01D02*
X344648Y137189D01*
G01D02*
X344654Y137194D01*
G01D02*
X344697Y137226D01*
G01D02*
X344742Y137260D01*
G01D02*
X344951Y137419D01*
G01D02*
G03X345003Y137464I-300J400D01*
G01D02*
X346525Y138986D01*
G01X341640Y152000D02*
X341953Y151687D01*
G01D02*
G03X343129Y151200I1176J1176D01*
G01D02*
X348422D01*
G01X339440Y152000D02*
G02X338052Y151425I-1388J1388D01*
G01D02*
X332829D01*
G01D02*
G02X331782Y151858I-1J1480D01*
G01D02*
X331040Y152601D01*
G01X339440Y149500D02*
G03X338052Y150075I-1388J-1388D01*
G01D02*
X333429D01*
G01D02*
G03X331679Y149350I0J-2475D01*
G01D02*
X330929Y148600D01*
G01X341640Y149500D02*
G02X342485Y149850I845J-845D01*
G01D02*
X348421D01*
G01X341640Y143000D02*
G02X343089Y143600I1449J-1449D01*
G01D02*
X345510D01*
G01D02*
G03X346926Y144186I1J2002D01*
G01X339440Y143000D02*
X338323D01*
G01D02*
G02X338040Y143117I0J401D01*
G01D02*
X337699Y143458D01*
G01D02*
G03X337416Y143575I-283J-284D01*
G01X339440Y145500D02*
X338323D01*
G01D02*
G03X338040Y145383I0J-401D01*
G01D02*
X337699Y145042D01*
G01D02*
G02X337416Y144925I-283J284D01*
G01X341640Y145500D02*
G03X342968Y144950I1328J1328D01*
G01D02*
X345510D01*
G01D02*
G03X345971Y145141I0J652D01*
G01D02*
X347388Y146558D01*
G01X344590Y138961D02*
X345570Y139941D01*
G01D02*
G02X347754Y140845I2183J-2184D01*
G01X339440Y139000D02*
X338524D01*
G01D02*
G03X337897Y138740I0J-886D01*
G01X341640Y165000D02*
G03X344175Y163950I2535J2535D01*
G01D02*
X344573D01*
G01D02*
G02X347335Y162806I0J-3907D01*
G01X331220Y164200D02*
G03X332242Y164624I-1J1446D01*
G01D02*
X332289Y164670D01*
G01D02*
G02X333229Y165140I922J-670D01*
G01D02*
X334429D01*
G01D02*
G02X335369Y164670I18J-1140D01*
G01D02*
G03X336309Y164200I922J670D01*
G01D02*
X337509D01*
G01D02*
G03X339440Y165000I0J2731D01*
G01X331219Y162850D02*
X338595D01*
G01D02*
G02X339440Y162500I0J-1195D01*
G01X341640D02*
G02X341881Y162600I241J-241D01*
G01D02*
X344572D01*
G01D02*
G02X346380Y161851I0J-2557D01*
G01D02*
X348680Y159551D01*
G01X341640Y171500D02*
X342499Y170641D01*
G01D02*
G03X342960Y170450I461J461D01*
G01D02*
X343230D01*
G01D02*
G02X346062Y169277I0J-4006D01*
G01D02*
X349107Y166232D01*
G01X332175Y171760D02*
G03X334129Y170950I1955J1954D01*
G01D02*
X338112D01*
G01D02*
G03X339440Y171500I0J1878D01*
G01X331220Y170805D02*
G03X334129Y169600I2909J2909D01*
G01D02*
X337991D01*
G01D02*
G02X339440Y169000I0J-2049D01*
G01X341640D02*
G02X341881Y169100I241J-241D01*
G01D02*
X343229D01*
G01D02*
G02X345107Y168322I0J-2656D01*
G01D02*
X348152Y165277D01*
G01X341640Y158500D02*
X341898Y158242D01*
G01D02*
G03X343809Y157450I1912J1911D01*
G01D02*
X346445D01*
G01X330038Y158940D02*
X331238D01*
G01D02*
G02X332178Y158470I18J-1140D01*
G01D02*
G03X333118Y158000I922J670D01*
G01D02*
X338233D01*
G01D02*
G03X339440Y158500I0J1707D01*
G01X337871Y156650D02*
G02X339440Y156000I0J-2219D01*
G01X341640D02*
G02X341881Y156100I241J-241D01*
G01D02*
X346446D01*
G01X341640Y175500D02*
G02X343089Y176100I1449J-1449D01*
G01D02*
X345698D01*
G01D02*
G02X347629Y175300I0J-2731D01*
G01X334246Y177484D02*
G03X337829Y176000I3583J3583D01*
G01D02*
X338233D01*
G01D02*
G02X339440Y175500I0J-1707D01*
G01X335201Y178439D02*
G03X337829Y177350I2629J2628D01*
G01D02*
X337871D01*
G01D02*
G03X339440Y178000I0J2219D01*
G01X341640D02*
X341717Y177923D01*
G01D02*
G03X342859Y177450I1142J1142D01*
G01D02*
X345699D01*
G01D02*
G02X348584Y176255I0J-4081D01*
G01X332379Y714661D02*
X355100Y691940D01*
G01X330866Y717504D02*
X331714Y716655D01*
G01D02*
G02X332046Y715658I-794J-818D01*
G01D02*
G03X332379Y714661I1126J-178D01*
G01X334465Y734811D02*
X359634Y709642D01*
G01X330109Y739167D02*
X330957Y738319D01*
G01D02*
G03X331954Y737986I819J793D01*
G01D02*
G02X332951Y737654I179J-1126D01*
G01D02*
X333800Y736806D01*
G01D02*
G02X334132Y735808I-794J-818D01*
G01D02*
G03X334465Y734811I1126J-178D01*
G01X331105Y749435D02*
X365595Y714945D01*
G01X342452Y749322D02*
X356595Y735179D01*
G01X330440Y751429D02*
G02X330773Y750432I-793J-819D01*
G01D02*
G03X331105Y749435I1126J-179D01*
G01X334589Y757185D02*
G03X335586Y756852I819J793D01*
G01D02*
G02X336583Y756520I179J-1126D01*
G01D02*
X337432Y755671D01*
G01D02*
G02X337764Y754674I-794J-818D01*
G01D02*
G03X338097Y753677I1126J-178D01*
G01D02*
X338945Y752829D01*
G01D02*
G03X339942Y752496I819J793D01*
G01D02*
G02X340939Y752164I179J-1126D01*
G01D02*
X341788Y751316D01*
G01D02*
G02X342120Y750319I-794J-818D01*
G01D02*
G03X342452Y749322I1126J-179D01*
G01X366673Y965811D02*
X330941D01*
G01X366674Y964461D02*
X330942D01*
G01X343812Y994068D02*
G02X342256Y990310I-5315J-1D01*
G01X345163Y994068D02*
G02X343211Y989355I-6665J0D01*
G01X330708Y1008860D02*
Y1001110D01*
G01D02*
G02X330308Y1000710I-400J0D01*
G01X342518Y1008860D02*
Y1001110D01*
G01D02*
G03X342918Y1000710I400J0D01*
G01D02*
X343413D01*
G01D02*
G02X343813Y1000310I0J-400D01*
G01D02*
Y994067D01*
G01D02*
X343812Y994068D01*
G01X346458Y1001110D02*
G02X346058Y1000710I-400J0D01*
G01D02*
X345563D01*
G01D02*
G03X345163Y1000310I0J-400D01*
G01D02*
Y994068D01*
G01X350399Y135429D02*
G02X352490Y136295I2091J-2091D01*
G01D02*
X357148D01*
G01D02*
G03X358563Y136881I0J2001D01*
G01D02*
X359167Y137485D01*
G01D02*
G02X359915Y137795I748J-747D01*
G01D02*
X360433D01*
G01X349444Y136384D02*
G02X352490Y137645I3045J-3046D01*
G01D02*
X357134D01*
G01D02*
X357284Y137795D01*
G01X348422Y151200D02*
G02X349629Y150700I0J-1707D01*
G01D02*
G03X350612Y150293I983J983D01*
G01D02*
X357043D01*
G01D02*
G03X357284Y150393I0J340D01*
G01X348421Y149850D02*
G02X348674Y149745I0J-357D01*
G01D02*
G03X350613Y148943I1937J1938D01*
G01D02*
X357631D01*
G01D02*
G03X357824Y149023I0J273D01*
G01D02*
X357904Y149103D01*
G01D02*
G03X358378Y149436I-715J1522D01*
G01D02*
X358975Y150033D01*
G01D02*
G02X359844Y150393I869J-869D01*
G01D02*
X360433D01*
G01X346926Y144186D02*
X348343Y145603D01*
G01D02*
G02X348803Y145794I461J-460D01*
G01D02*
X357189D01*
G01D02*
G03X358378Y146287I-1J1682D01*
G01D02*
X358975Y146884D01*
G01D02*
G02X359844Y147244I869J-869D01*
G01D02*
X360433D01*
G01X347388Y146558D02*
G02X348803Y147144I1415J-1415D01*
G01D02*
X357184D01*
G01D02*
X357284Y147244D01*
G01X347754Y140845D02*
X357043D01*
G01D02*
G03X357284Y140945I0J340D01*
G01X346525Y138986D02*
G02X347754Y139495I1229J-1229D01*
G01D02*
X357043D01*
G01D02*
G03X357184I71J1691D01*
G01D02*
G03Y139500I-148J2D01*
G01D02*
X357189Y139495D01*
G01D02*
G03X358378Y139988I-1J1682D01*
G01D02*
X358975Y140585D01*
G01D02*
G02X359844Y140945I869J-869D01*
G01D02*
X360433D01*
G01X350437Y172492D02*
G02X351029Y171063I-1429J-1429D01*
G01D02*
G03X354292Y167800I3263J0D01*
G01D02*
X358929D01*
G01D02*
G03X359983Y168236I1J1490D01*
G01D02*
X360300Y168554D01*
G01D02*
G03X360433Y169217I-1588J663D01*
G01D02*
Y169291D01*
G01X351392Y173447D02*
G02X352379Y171063I-2384J-2383D01*
G01D02*
G03X354292Y169150I1913J0D01*
G01D02*
X356944D01*
G01D02*
G03X357067Y169166I0J481D01*
G01D02*
G03X357171Y169207I-123J465D01*
G01D02*
G03X357284Y169291I-227J424D01*
G01X347335Y162806D02*
X349635Y160506D01*
G01D02*
G03X351238Y159842I1603J1603D01*
G01D02*
X357284D01*
G01X348680Y159551D02*
G03X351237Y158492I2557J2558D01*
G01D02*
X356654D01*
G01D02*
X356704Y158442D01*
G01D02*
X357864D01*
G01D02*
X357914Y158492D01*
G01D02*
X357985D01*
G01D02*
G03X358248Y158505I1J2651D01*
G01D02*
G03X359860Y159268I-262J2638D01*
G01D02*
X360433Y159842D01*
G01X349107Y166232D02*
G03X349567Y166041I461J460D01*
G01D02*
X357184D01*
G01D02*
X357284Y166141D01*
G01X348152Y165277D02*
G03X349567Y164691I1415J1415D01*
G01D02*
X358391D01*
G01D02*
G03X359400Y165109I0J1427D01*
G01D02*
X359872Y165581D01*
G01D02*
X360433Y166141D01*
G01X346445Y157450D02*
G02X347884Y156855I2J-2033D01*
G01D02*
G03X348274Y156693I391J390D01*
G01D02*
X357284D01*
G01X346446Y156100D02*
G02X346929Y155900I0J-683D01*
G01D02*
G03X348274Y155343I1345J1345D01*
G01D02*
X357838D01*
G01D02*
G03X358579Y155650I0J1048D01*
G01D02*
X359379Y156450D01*
G01D02*
G02X359966Y156693I587J-587D01*
G01D02*
X360433D01*
G01X347629Y175300D02*
X350437Y172492D01*
G01X348584Y176255D02*
X351392Y173447D01*
G01X355100Y691940D02*
G03X356097Y691608I818J794D01*
G01D02*
G02X357094Y691275I178J-1126D01*
G01D02*
X357942Y690427D01*
G01D02*
G02X358275Y689430I-793J-819D01*
G01D02*
G03X358607Y688433I1126J-179D01*
G01D02*
X359456Y687584D01*
G01D02*
G03X360453Y687252I818J794D01*
G01D02*
G02X361450Y686920I179J-1126D01*
G01D02*
X362298Y686071D01*
G01D02*
G02X362631Y685074I-793J-819D01*
G01D02*
G03X362963Y684077I1126J-179D01*
G01X352203Y706032D02*
G03X353200Y705699I819J793D01*
G01D02*
G02X354197Y705367I179J-1126D01*
G01D02*
X355046Y704518D01*
G01D02*
G02X355378Y703521I-794J-818D01*
G01D02*
G03X355711Y702524I1126J-178D01*
G01D02*
X356559Y701676D01*
G01D02*
G03X357556Y701344I818J794D01*
G01D02*
G02X358553Y701011I178J-1126D01*
G01D02*
X359402Y700163D01*
G01D02*
G02X359734Y699166I-794J-818D01*
G01D02*
G03X360066Y698169I1126J-179D01*
G01D02*
X360915Y697320D01*
G01D02*
G03X361912Y696988I818J794D01*
G01D02*
G02X362909Y696655I178J-1126D01*
G01X359634Y709642D02*
G03X360631Y709310I818J794D01*
G01D02*
G02X361628Y708978I179J-1126D01*
G01D02*
X362476Y708129D01*
G01D02*
G02X362809Y707132I-793J-819D01*
G01X356595Y735179D02*
G03X357592Y734847I818J794D01*
G01D02*
G02X358589Y734515I179J-1126D01*
G01D02*
X359437Y733666D01*
G01D02*
G02X359770Y732669I-793J-819D01*
G01D02*
G03X360102Y731672I1126J-179D01*
G01D02*
X360950Y730824D01*
G01D02*
G03X361947Y730491I819J793D01*
G01D02*
G02X362944Y730159I179J-1126D01*
G01X358005Y744649D02*
G03X359002Y744317I818J794D01*
G01D02*
G02X359999Y743984I178J-1126D01*
G01D02*
X360848Y743136D01*
G01D02*
G02X361180Y742139I-794J-818D01*
G01D02*
G03X361512Y741142I1126J-179D01*
G01D02*
X362361Y740293D01*
G01D02*
G03X363358Y739961I818J794D01*
G01X346458Y1008860D02*
Y1001110D01*
G01X369882Y137795D02*
X371456Y136221D01*
G01X366733Y137795D02*
X366747D01*
G01D02*
X368296Y136246D01*
G01X368305Y139401D02*
Y139505D01*
G01D02*
X369745Y140945D01*
G01D02*
X369882D01*
G01X368314Y142505D02*
X368273D01*
G01D02*
X366733Y140965D01*
G01D02*
Y140945D01*
G01Y147244D02*
X366789Y147300D01*
G01D02*
X367235D01*
G01D02*
G02X367311Y147285I-1J-206D01*
G01D02*
X367433Y147237D01*
G01D02*
G03X367572Y147212I139J374D01*
G01D02*
X367633D01*
G01D02*
X368213Y146632D01*
G01D02*
G03X368220Y146569I278J-1D01*
G01D02*
X368299Y146228D01*
G01D02*
G02X368314Y146096I-568J-131D01*
G01D02*
Y145680D01*
G01X369882Y147244D02*
X371459Y145667D01*
G01D02*
X371493D01*
G01X368329Y151956D02*
X368190Y151817D01*
G01D02*
Y151776D01*
G01D02*
X366807Y150393D01*
G01D02*
X366733D01*
G01X369882D02*
Y149860D01*
G01D02*
G02X369736Y149507I-500J0D01*
G01D02*
X369209Y148980D01*
G01D02*
G02X368856Y148834I-353J354D01*
G01D02*
X368340D01*
G01D02*
X368333Y148827D01*
G01X365140Y155100D02*
X365502D01*
G01D02*
G03X366067Y155334I0J799D01*
G01X369882Y156656D02*
X368333Y155107D01*
G01X368271Y158268D02*
X368403Y158400D01*
G01D02*
X368440D01*
G01D02*
X369882Y159842D01*
G01X366733D02*
X366768D01*
G01D02*
X368326Y161400D01*
G01X366067Y155334D02*
X366499Y155766D01*
G01D02*
G03X366733Y156331I-565J565D01*
G01D02*
Y156693D01*
G01X369882D02*
Y156656D01*
G01X368325Y164585D02*
X369881Y166141D01*
G01D02*
X369882D01*
G01X366733D02*
Y165211D01*
G01D02*
G02X366587Y164858I-500J0D01*
G01D02*
X366429Y164700D01*
G01D02*
G02X366076Y164554I-353J354D01*
G01D02*
X365158D01*
G01X369882Y169291D02*
X369820D01*
G01D02*
X368334Y167805D01*
G01D02*
Y167706D01*
G01X366733Y169291D02*
X366770D01*
G01D02*
X368309Y170830D01*
G01X362963Y684077D02*
X379906Y667134D01*
G01X364422Y693813D02*
X378630Y679605D01*
G01D02*
G03X379627Y679273I818J794D01*
G01X362909Y696655D02*
X363757Y695807D01*
G01D02*
G02X364090Y694810I-793J-819D01*
G01D02*
G03X364422Y693813I1126J-179D01*
G01X371853Y697423D02*
X386580Y682696D01*
G01X362809Y707132D02*
G03X363141Y706135I1126J-179D01*
G01D02*
X363990Y705286D01*
G01D02*
G03X364987Y704954I818J794D01*
G01D02*
G02X365984Y704622I179J-1126D01*
G01D02*
X366832Y703773D01*
G01D02*
G02X367164Y702776I-794J-818D01*
G01D02*
G03X367497Y701779I1126J-178D01*
G01D02*
X368345Y700931D01*
G01D02*
G03X369342Y700598I819J793D01*
G01D02*
G02X370339Y700266I179J-1126D01*
G01D02*
X371188Y699417D01*
G01D02*
G02X371520Y698420I-794J-818D01*
G01D02*
G03X371853Y697423I1126J-178D01*
G01X368437Y713432D02*
G02X368770Y712435I-793J-819D01*
G01D02*
G03X369102Y711438I1126J-179D01*
G01D02*
X369951Y710589D01*
G01D02*
G03X370948Y710257I818J794D01*
G01D02*
G02X371945Y709925I179J-1126D01*
G01D02*
X372793Y709076D01*
G01D02*
G02X373125Y708079I-794J-818D01*
G01D02*
G03X373458Y707082I1126J-178D01*
G01D02*
X374306Y706234D01*
G01D02*
G03X375303Y705901I819J793D01*
G01D02*
G02X376300Y705569I179J-1126D01*
G01D02*
X377149Y704720D01*
G01D02*
G02X377481Y703723I-794J-818D01*
G01D02*
G03X377814Y702726I1126J-178D01*
G01D02*
X388394Y692146D01*
G01X368813Y722961D02*
X382956Y708818D01*
G01X365595Y714945D02*
G03X366592Y714613I818J794D01*
G01D02*
G02X367589Y714281I179J-1126D01*
G01D02*
X368437Y713432D01*
G01X362944Y730159D02*
X363793Y729310D01*
G01D02*
G02X364125Y728313I-794J-818D01*
G01D02*
G03X364458Y727316I1126J-178D01*
G01D02*
X365306Y726468D01*
G01D02*
G03X366303Y726136I818J794D01*
G01D02*
G02X367300Y725803I178J-1126D01*
G01D02*
X368149Y724955D01*
G01D02*
G02X368481Y723958I-794J-818D01*
G01D02*
G03X368813Y722961I1126J-179D01*
G01X370224Y732430D02*
X384366Y718288D01*
G01X363358Y739961D02*
G02X364355Y739628I178J-1126D01*
G01D02*
X365203Y738780D01*
G01D02*
G02X365536Y737783I-793J-819D01*
G01D02*
G03X365868Y736786I1126J-179D01*
G01D02*
X366717Y735937D01*
G01D02*
G03X367714Y735605I818J794D01*
G01D02*
G02X368711Y735273I179J-1126D01*
G01D02*
X369559Y734424D01*
G01D02*
G02X369892Y733427I-793J-819D01*
G01D02*
G03X370224Y732430I1126J-179D01*
G01X379993Y975115D02*
X373529Y968651D01*
G01D02*
G02X366673Y965811I-6856J6856D01*
G01X380948Y974160D02*
X374484Y967696D01*
G01D02*
G02X366674Y964461I-7810J7811D01*
G01X383081Y664624D02*
G03X383413Y663627I1126J-179D01*
G01D02*
X384261Y662779D01*
G01D02*
G03X385259Y662446I819J793D01*
G01D02*
G02X386256Y662114I179J-1126D01*
G01D02*
X387104Y661265D01*
G01D02*
G02X387436Y660268I-794J-818D01*
G01D02*
G03X387769Y659271I1126J-178D01*
G01D02*
X388617Y658423D01*
G01D02*
G03X389614Y658090I819J793D01*
G01D02*
G02X390611Y657758I179J-1126D01*
G01D02*
X391460Y656910D01*
G01D02*
G02X391792Y655913I-794J-818D01*
G01D02*
G03X392125Y654915I1126J-179D01*
G01D02*
X399880Y647160D01*
G01X382137Y676098D02*
X407040Y651195D01*
G01X379906Y667134D02*
G03X380903Y666802I818J794D01*
G01D02*
G02X381900Y666470I179J-1126D01*
G01D02*
X382748Y665621D01*
G01D02*
G02X383081Y664624I-793J-819D01*
G01X379627Y679273D02*
G02X380624Y678941I179J-1126D01*
G01D02*
X381472Y678092D01*
G01D02*
G02X381805Y677095I-793J-819D01*
G01D02*
G03X382137Y676098I1126J-179D01*
G01X389423Y681183D02*
G02X389755Y680186I-794J-818D01*
G01D02*
G03X390087Y679189I1126J-179D01*
G01D02*
X414574Y654702D01*
G01X386580Y682696D02*
G03X387577Y682364I818J794D01*
G01D02*
G02X388574Y682031I178J-1126D01*
G01D02*
X389423Y681183D01*
G01X388394Y692146D02*
G03X389391Y691813I819J793D01*
G01D02*
G02X390388Y691481I179J-1126D01*
G01D02*
X391237Y690633D01*
G01D02*
G02X391569Y689636I-794J-818D01*
G01D02*
G03X391901Y688639I1126J-179D01*
G01D02*
X420363Y660177D01*
G01X394842Y697597D02*
G03X395174Y696600I1126J-179D01*
G01D02*
X427976Y663798D01*
G01X382956Y708818D02*
G03X383953Y708486I818J794D01*
G01D02*
G02X384950Y708154I179J-1126D01*
G01D02*
X385798Y707305D01*
G01D02*
G02X386130Y706308I-794J-818D01*
G01D02*
G03X386463Y705311I1126J-178D01*
G01D02*
X387311Y704463D01*
G01D02*
G03X388308Y704130I819J793D01*
G01D02*
G02X389305Y703798I179J-1126D01*
G01D02*
X390154Y702949D01*
G01D02*
G02X390486Y701952I-794J-818D01*
G01D02*
G03X390819Y700955I1126J-178D01*
G01D02*
X391667Y700107D01*
G01D02*
G03X392664Y699775I818J794D01*
G01D02*
G02X393661Y699442I178J-1126D01*
G01D02*
X394510Y698594D01*
G01D02*
G02X394842Y697597I-794J-818D01*
G01X389719Y713600D02*
G02X390716Y713268I179J-1126D01*
G01D02*
X391564Y712419D01*
G01D02*
G02X391897Y711422I-793J-819D01*
G01D02*
G03X392229Y710425I1126J-179D01*
G01D02*
X393078Y709576D01*
G01D02*
G03X394075Y709244I818J794D01*
G01D02*
G02X395072Y708912I179J-1126D01*
G01D02*
X395920Y708063D01*
G01X384366Y718288D02*
G03X385363Y717956I818J794D01*
G01D02*
G02X386360Y717623I178J-1126D01*
G01D02*
X387209Y716775D01*
G01D02*
G02X387541Y715778I-794J-818D01*
G01D02*
G03X387873Y714781I1126J-179D01*
G01D02*
X388722Y713932D01*
G01D02*
G03X389719Y713600I818J794D01*
G01X385816Y977527D02*
G03X379993Y975115I0J-8236D01*
G01X385816Y976176D02*
G03X380948Y974160I0J-6885D01*
G01X394996Y1000310D02*
Y989518D01*
G01D02*
G02X392044Y982392I-10077J0D01*
G01D02*
X388142Y978490D01*
G01D02*
G02X385816Y977527I-2325J2326D01*
G01X396346Y989517D02*
G02X392999Y981437I-11427J0D01*
G01D02*
X389097Y977535D01*
G01D02*
G02X385816Y976176I-3281J3281D01*
G01X393703Y1008860D02*
Y1001110D01*
G01D02*
G03X394103Y1000710I400J0D01*
G01D02*
X394596D01*
G01D02*
G02X394996Y1000310I0J-400D01*
G01X409340Y434801D02*
X414128Y430014D01*
G01X403912Y442143D02*
X414654Y431401D01*
G01X400555Y448900D02*
Y448024D01*
G01D02*
G03X400843Y447330I980J0D01*
G01D02*
X400962Y447211D01*
G01D02*
G02X401130Y446804I-409J-407D01*
G01D02*
Y445599D01*
G01D02*
G03X402957Y441188I6239J0D01*
G01D02*
X404220Y439922D01*
G01D02*
X405466Y438676D01*
G01D02*
X405935Y438208D01*
G01D02*
X409340Y434801D01*
G01X403055Y448900D02*
Y448024D01*
G01D02*
G02X402768Y447330I-983J0D01*
G01D02*
X402649Y447211D01*
G01D02*
G03X402480Y446803I408J-408D01*
G01D02*
Y445600D01*
G01D02*
G03X403912Y442143I4889J0D01*
G01X407555Y448900D02*
Y447927D01*
G01D02*
G03X407701Y447574I500J0D01*
G01D02*
X407984Y447291D01*
G01D02*
G02X408130Y446938I-354J-353D01*
G01D02*
Y445408D01*
G01D02*
G03X409253Y442698I3834J1D01*
G01D02*
X417633Y434317D01*
G01X410055Y448900D02*
Y447927D01*
G01D02*
G02X409909Y447574I-500J0D01*
G01D02*
X409626Y447291D01*
G01D02*
G03X409480Y446938I354J-353D01*
G01D02*
Y445409D01*
G01D02*
G03X410208Y443653I2484J1D01*
G01D02*
X418588Y435272D01*
G01X401130Y640882D02*
Y452488D01*
G01D02*
G02X400555Y451100I-1963J0D01*
G01X402480Y640883D02*
Y452870D01*
G01D02*
G03X403055Y451100I3012J0D01*
G01X408130Y645303D02*
Y452307D01*
G01D02*
G02X407843Y451612I-982J-1D01*
G01D02*
X407635Y451405D01*
G01D02*
G03X407555Y451212I193J-193D01*
G01D02*
Y451100D01*
G01X409480Y645304D02*
Y452489D01*
G01D02*
G03X409967Y451313I1663J0D01*
G01D02*
G02X410055Y451100I-214J-213D01*
G01X398925Y646205D02*
G02X401130Y640882I-5323J-5323D01*
G01X399880Y647160D02*
G02X402480Y640883I-6278J-6277D01*
G01X406085Y650240D02*
G02X408130Y645303I-4937J-4937D01*
G01X407040Y651195D02*
G02X409480Y645304I-5892J-5891D01*
G01X396585Y706069D02*
X435672Y666982D01*
G01X395920Y708063D02*
G02X396252Y707066I-794J-818D01*
G01D02*
G03X396585Y706069I1126J-178D01*
G01X408838Y819800D02*
G03X420766Y791002I40726J-1D01*
G01X410188Y819800D02*
G03X421721Y791957I39376J0D01*
G01X408838Y874701D02*
Y819800D01*
G01X410188Y850358D02*
Y819800D01*
G01Y861478D02*
G03X410658Y860538I1140J-18D01*
G01D02*
G02X411128Y859598I-670J-922D01*
G01D02*
Y858398D01*
G01D02*
G02X410658Y857458I-1140J-18D01*
G01D02*
G03X410188Y856518I670J-922D01*
G01D02*
Y855318D01*
G01D02*
G03X410658Y854378I1140J-18D01*
G01D02*
G02X411128Y853438I-670J-922D01*
G01D02*
Y852238D01*
G01D02*
G02X410658Y851298I-1140J-18D01*
G01D02*
G03X410188Y850358I670J-922D01*
G01X437827Y905042D02*
X409793Y877008D01*
G01D02*
G03X408838Y874701I2307J-2306D01*
G01X438782Y904087D02*
X410748Y876053D01*
G01D02*
G03X410188Y874701I1352J-1352D01*
G01D02*
Y873798D01*
G01D02*
G03X410658Y872858I1140J-18D01*
G01D02*
G02X411128Y871918I-670J-922D01*
G01D02*
Y870718D01*
G01D02*
G02X410658Y869778I-1140J-18D01*
G01D02*
G03X410188Y868838I670J-922D01*
G01D02*
Y867638D01*
G01D02*
G03X410658Y866698I1140J-18D01*
G01D02*
G02X411128Y865758I-670J-922D01*
G01D02*
Y864558D01*
G01D02*
G02X410658Y863618I-1140J-18D01*
G01D02*
G03X410188Y862678I670J-922D01*
G01D02*
Y861478D01*
G01X396346Y1000310D02*
Y989517D01*
G01X397638Y1008860D02*
Y1001110D01*
G01D02*
G02X397238Y1000710I-400J0D01*
G01D02*
X396746D01*
G01D02*
G03X396346Y1000310I0J-400D01*
G01X426574Y402953D02*
X424605Y404922D01*
G01X426574Y406890D02*
X424605Y408859D01*
G01X422637Y402953D02*
X420668Y404922D01*
G01X422637Y406890D02*
X420668Y408859D01*
G01X424145Y419570D02*
G03X425826Y415512I5739J0D01*
G01D02*
X426574Y414764D01*
G01X414128Y430014D02*
X416019Y428124D01*
G01D02*
X416928Y427216D01*
G01D02*
X420534Y423611D01*
G01D02*
G02X420544Y423601I-278J-288D01*
G01D02*
G02X420553Y423591I-292J-272D01*
G01D02*
G02X420574Y423568I-284J-280D01*
G01D02*
G02X420612Y423521I-291J-274D01*
G01D02*
G02X420676Y423425I-294J-265D01*
G01D02*
G02X421137Y422313I-1201J-1150D01*
G01D02*
G03X421628Y421127I1678J0D01*
G01D02*
X422136Y420619D01*
G01D02*
G02X422637Y419410I-1209J-1209D01*
G01D02*
Y418701D01*
G01X414654Y431401D02*
X414655D01*
G01D02*
X421602Y424454D01*
G01D02*
G02X422487Y422788I-2116J-2192D01*
G01D02*
G02X422451Y422782I-61J257D01*
G01D02*
X422637Y422638D01*
G01X417633Y434317D02*
X418232Y433718D01*
G01D02*
G02X418695Y432599I-1119J-1118D01*
G01D02*
G03X420038Y429358I4583J1D01*
G01D02*
X423466Y425930D01*
G01D02*
G02X424141Y424418I-1641J-1639D01*
G01D02*
G02X424145Y424290I-2316J-136D01*
G01D02*
Y419570D01*
G01X419187Y434673D02*
G02X420046Y432599I-2074J-2074D01*
G01D02*
G03X420993Y430313I3233J0D01*
G01D02*
X423635Y427671D01*
G01D02*
G02X425065Y424470I-2868J-3201D01*
G01D02*
Y420163D01*
G01D02*
G03X425109Y419831I1263J-2D01*
G01D02*
G03X425215Y419565I1219J332D01*
G01D02*
G03X425435Y419270I1112J600D01*
G01D02*
X425601Y419104D01*
G01D02*
G03X426574Y418701I973J973D01*
G01X416567Y442629D02*
X426606Y432590D01*
G01D02*
G02X428673Y427600I-4990J-4990D01*
G01X417522Y443584D02*
X427561Y433545D01*
G01D02*
G02X430023Y427600I-5945J-5944D01*
G01X418588Y435272D02*
X419187Y434673D01*
G01X414555Y448900D02*
Y448077D01*
G01D02*
G03X414701Y447724I500J0D01*
G01D02*
X414984Y447441D01*
G01D02*
G02X415130Y447088I-354J-353D01*
G01D02*
Y446099D01*
G01D02*
G03X416567Y442629I4909J0D01*
G01X417055Y448900D02*
Y448097D01*
G01D02*
G02X416909Y447744I-500J0D01*
G01D02*
X416626Y447461D01*
G01D02*
G03X416480Y447108I354J-353D01*
G01D02*
Y446100D01*
G01D02*
G03X417522Y443584I3559J0D01*
G01X421555Y448900D02*
Y448770D01*
G01D02*
G03X421647Y448548I314J0D01*
G01D02*
X422059Y448136D01*
G01D02*
G02X422205Y447783I-354J-353D01*
G01D02*
Y445853D01*
G01D02*
G03X423875Y441821I5703J0D01*
G01D02*
X427339Y438357D01*
G01D02*
G02X427464Y438230I-10074J-10041D01*
G01D02*
G02X427607Y438080I-10223J-9889D01*
G01D02*
X427616Y438070D01*
G01D02*
G03X427626Y438060I288J278D01*
G01D02*
X430369Y435317D01*
G01X424055Y448900D02*
Y448607D01*
G01D02*
G02X423909Y448254I-500J0D01*
G01D02*
X423701Y448046D01*
G01D02*
G03X423555Y447693I354J-353D01*
G01D02*
Y445854D01*
G01D02*
G03X424830Y442776I4353J0D01*
G01D02*
X428295Y439311D01*
G01D02*
X428296D01*
G01D02*
G02X428591Y439006I-11046J-10979D01*
G01X415130Y650099D02*
Y452982D01*
G01D02*
G02X414843Y452288I-983J0D01*
G01D02*
G03X414555Y451593I695J-695D01*
G01D02*
Y451100D01*
G01X416480Y650099D02*
Y452681D01*
G01D02*
G03X416767Y451988I980J0D01*
G01D02*
G02X417055Y451293I-695J-695D01*
G01D02*
Y451100D01*
G01X422130Y652651D02*
Y452882D01*
G01D02*
G02X421843Y452188I-983J0D01*
G01D02*
X421838Y452183D01*
G01D02*
G03X421555Y451500I683J-683D01*
G01D02*
Y451100D01*
G01X423480Y652652D02*
Y452606D01*
G01D02*
G03X423766Y451913I983J0D01*
G01D02*
X423767Y451912D01*
G01D02*
G02X424055Y451218I-692J-694D01*
G01D02*
Y451100D01*
G01X413619Y653747D02*
G02X415130Y650099I-3648J-3648D01*
G01X414574Y654702D02*
G02X416480Y650099I-4603J-4602D01*
G01X419408Y659222D02*
G02X422130Y652651I-6571J-6571D01*
G01X420363Y660177D02*
G02X423480Y652652I-7526J-7526D01*
G01X427021Y662843D02*
G02X429130Y657751I-5092J-5092D01*
G01X427976Y663798D02*
G02X430480Y657751I-6047J-6046D01*
G01X420766Y791002D02*
X439353Y772415D01*
G01X421721Y791957D02*
X424736Y788942D01*
G01D02*
G03X425733Y788609I819J793D01*
G01D02*
G02X426730Y788277I179J-1126D01*
G01D02*
X427579Y787428D01*
G01D02*
G02X427911Y786431I-794J-818D01*
G01D02*
G03X428244Y785434I1126J-178D01*
G01D02*
X429092Y784586D01*
G01X427853Y847833D02*
Y802400D01*
G01D02*
G02X427453Y802000I-400J0D01*
G01D02*
X425278D01*
G01X432045Y857955D02*
G03X427853Y847833I10122J-10121D01*
G01X446259Y402953D02*
X444290Y404922D01*
G01X446259Y406890D02*
X444290Y408859D01*
G01X442322Y402953D02*
X440353Y404922D01*
G01X442322Y406890D02*
X440353Y408859D01*
G01X438385Y402953D02*
X436416Y404922D01*
G01X438385Y406890D02*
X436416Y408859D01*
G01X434448Y402953D02*
X432479Y404922D01*
G01X434448Y406890D02*
X432479Y408859D01*
G01X430511Y402953D02*
X428542Y404922D01*
G01X430511Y406890D02*
X428542Y408859D01*
G01X432023Y418550D02*
G03X432985Y416226I3286J-1D01*
G01D02*
X434448Y414764D01*
G01X439885Y419720D02*
G03X441666Y415420I6081J0D01*
G01D02*
X442322Y414764D01*
G01X428673Y427600D02*
Y420979D01*
G01D02*
G03X428819Y420626I500J0D01*
G01D02*
X430429Y419016D01*
G01D02*
G02X430511Y418817I-199J-198D01*
G01D02*
Y418701D01*
G01X430023Y427600D02*
Y423179D01*
G01D02*
G03X430169Y422826I500J0D01*
G01D02*
X430357Y422638D01*
G01D02*
X430511D01*
G01X430369Y435317D02*
G02X431595Y432359I-2957J-2958D01*
G01D02*
Y428010D01*
G01D02*
G03X431774Y426434I7027J0D01*
G01D02*
G02X432011Y424696I-6257J-1738D01*
G01D02*
Y420902D01*
G01D02*
X432023Y420890D01*
G01D02*
Y418550D01*
G01X431324Y436272D02*
G02X432945Y432360I-3912J-3913D01*
G01D02*
Y420954D01*
G01D02*
G03X433226Y419923I2032J0D01*
G01D02*
X434448Y418701D01*
G01X435575Y436121D02*
G02X437035Y432596I-3525J-3525D01*
G01D02*
Y424362D01*
G01D02*
G02X436765Y423710I-922J0D01*
G01D02*
G03X436495Y423058I652J-652D01*
G01D02*
Y421347D01*
G01D02*
G03X437227Y419579I2501J0D01*
G01D02*
X438105Y418701D01*
G01D02*
X438385D01*
G01X436530Y437076D02*
G02X438385Y432596I-4480J-4479D01*
G01D02*
Y424288D01*
G01D02*
X438384D01*
G01D02*
X438385Y422638D01*
G01X439885Y437143D02*
Y419720D01*
G01X441235Y437143D02*
Y429138D01*
G01D02*
G02X441073Y428468I-1468J0D01*
G01D02*
G03X440805Y427821I647J-647D01*
G01D02*
Y419774D01*
G01D02*
G03X441148Y418946I1171J0D01*
G01D02*
G03X441898Y418701I750J1025D01*
G01D02*
X442322D01*
G01X444355Y440784D02*
Y423910D01*
G01D02*
G03X444407Y423302I3549J-3D01*
G01D02*
Y423172D01*
G01D02*
G03X446259Y418701I6323J0D01*
G01X428591Y439006D02*
X431324Y436272D01*
G01X428555Y448900D02*
Y448117D01*
G01D02*
G03X428701Y447764I500J0D01*
G01D02*
X428952Y447513D01*
G01D02*
G02X429098Y447160I-354J-353D01*
G01D02*
Y445301D01*
G01D02*
G03X431007Y440689I6521J-2D01*
G01D02*
X435575Y436121D01*
G01X431055Y448900D02*
Y447987D01*
G01D02*
G02X430909Y447634I-500J0D01*
G01D02*
X430594Y447319D01*
G01D02*
G03X430448Y446966I354J-353D01*
G01D02*
Y445300D01*
G01D02*
G03X431962Y441644I5171J0D01*
G01D02*
X436530Y437076D01*
G01X435555Y448900D02*
Y447827D01*
G01D02*
G03X435701Y447474I500J0D01*
G01D02*
X436009Y447166D01*
G01D02*
G02X436155Y446813I-354J-353D01*
G01D02*
Y445161D01*
G01D02*
G03X437812Y441158I5659J-2D01*
G01D02*
X438512Y440458D01*
G01D02*
G02X439885Y437143I-3315J-3315D01*
G01X438055Y448900D02*
Y447867D01*
G01D02*
G02X437909Y447514I-500J0D01*
G01D02*
X437651Y447256D01*
G01D02*
G03X437505Y446903I354J-353D01*
G01D02*
Y445160D01*
G01D02*
G03X438767Y442113I4309J0D01*
G01D02*
X439467Y441413D01*
G01D02*
G02X441235Y437143I-4270J-4269D01*
G01X442555Y448900D02*
Y448024D01*
G01D02*
G03X442843Y447330I980J0D01*
G01D02*
X442962Y447211D01*
G01D02*
G02X443130Y446804I-409J-407D01*
G01D02*
Y443742D01*
G01D02*
G03X444137Y441307I3444J-2D01*
G01D02*
G02X444355Y440784I-522J-525D01*
G01X445055Y448024D02*
G02X444768Y447330I-983J0D01*
G01D02*
X444649Y447211D01*
G01D02*
G03X444480Y446803I408J-408D01*
G01D02*
Y443742D01*
G01D02*
G03X445093Y442262I2093J0D01*
G01X429130Y657751D02*
Y452707D01*
G01D02*
G02X428843Y452012I-982J-1D01*
G01D02*
X428777Y451946D01*
G01D02*
G03X428555Y451412I531J-534D01*
G01D02*
Y451100D01*
G01X430480Y657751D02*
Y452606D01*
G01D02*
G03X430766Y451913I983J0D01*
G01D02*
X430767Y451912D01*
G01D02*
G02X431055Y451218I-692J-694D01*
G01D02*
Y451100D01*
G01X436130Y662616D02*
Y452482D01*
G01D02*
G02X435843Y451788I-983J0D01*
G01D02*
X435696Y451641D01*
G01D02*
G03X435555Y451300I342J-341D01*
G01D02*
Y451100D01*
G01X437480Y662617D02*
Y452506D01*
G01D02*
G03X437766Y451813I983J0D01*
G01D02*
X437767Y451812D01*
G01D02*
G02X438055Y451118I-692J-694D01*
G01D02*
Y451100D01*
G01X443130Y763297D02*
Y452706D01*
G01D02*
G02X442843Y452013I-980J0D01*
G01D02*
G03X442555Y451318I695J-695D01*
G01D02*
Y451100D01*
G01X444480Y763298D02*
Y452488D01*
G01D02*
G03X444825Y451655I1178J0D01*
G01X434717Y666027D02*
G02X436130Y662616I-3411J-3411D01*
G01X435672Y666982D02*
G02X437480Y662617I-4366J-4365D01*
G01X439353Y772415D02*
G02X443130Y763297I-9118J-9118D01*
G01X435442Y779565D02*
X436291Y778717D01*
G01D02*
G02X436623Y777720I-794J-818D01*
G01D02*
G03X436955Y776723I1126J-179D01*
G01D02*
X440308Y773370D01*
G01D02*
G02X444480Y763298I-10073J-10073D01*
G01X429092Y784586D02*
G03X430089Y784253I819J793D01*
G01D02*
G02X431086Y783921I179J-1126D01*
G01D02*
X431935Y783073D01*
G01D02*
G02X432267Y782076I-794J-818D01*
G01D02*
G03X432599Y781079I1126J-179D01*
G01D02*
X433448Y780230D01*
G01D02*
G03X434445Y779898I818J794D01*
G01D02*
G02X435442Y779565I178J-1126D01*
G01X442328Y806897D02*
Y794100D01*
G01D02*
G03X447861Y780742I18891J0D01*
G01X440978Y806822D02*
Y794100D01*
G01D02*
G03X446906Y779787I20242J-1D01*
G01X438278Y805250D02*
Y802100D01*
G01X444778Y805250D02*
Y802100D01*
G01X429203Y847833D02*
Y802400D01*
G01D02*
G03X429603Y802000I400J0D01*
G01D02*
X431778D01*
G01X444778Y808750D02*
X444162D01*
G01D02*
G03X442935Y808362I0J-2134D01*
G01D02*
G03X442328Y806897I1465J-1465D01*
G01X438278Y808750D02*
X439109D01*
G01D02*
G02X440332Y808382I-1J-2219D01*
G01D02*
G02X440978Y806822I-1560J-1560D01*
G01X445875Y824875D02*
X443500Y822500D01*
G01D02*
G03X441000Y816464I6036J-6036D01*
G01D02*
Y814500D01*
G01D02*
G02X438750Y812250I-2250J0D01*
G01D02*
X438278D01*
G01X446830Y823920D02*
X444455Y821545D01*
G01D02*
G03X442351Y816464I5081J-5080D01*
G01D02*
X442350Y816463D01*
G01D02*
Y813331D01*
G01D02*
G03X442584Y812766I799J0D01*
G01D02*
X442866Y812484D01*
G01D02*
G03X443431Y812250I565J565D01*
G01D02*
X444778D01*
G01X433650Y861829D02*
G02X432045Y857955I-5478J0D01*
G01X435000Y861828D02*
G02X433000Y857000I-6828J0D01*
G01D02*
G03X429203Y847833I9167J-9167D01*
G01X444886Y875779D02*
G02X444698Y875750I-188J595D01*
G01D02*
X444278D01*
G01X433650Y879564D02*
Y861829D01*
G01X435000Y878500D02*
Y861828D01*
G01X444278Y872250D02*
X444697D01*
G01D02*
G02X445262Y872016I0J-799D01*
G01X444278Y879250D02*
Y883000D01*
G01X431278D02*
X432898Y881380D01*
G01D02*
G02X433650Y879564I-1817J-1816D01*
G01X437778Y883000D02*
X436218Y881439D01*
G01D02*
G03X435000Y878500I2939J-2940D01*
G01X438828Y974066D02*
Y907458D01*
G01D02*
G02X437827Y905042I-3416J0D01*
G01X440178Y974067D02*
Y907457D01*
G01D02*
G02X438782Y904087I-4766J0D01*
G01X435962Y980985D02*
G02X438828Y974066I-6919J-6919D01*
G01X436917Y981940D02*
G02X440178Y974067I-7874J-7873D01*
G01X430428Y1000310D02*
Y990623D01*
G01D02*
G03X433329Y983618I9906J-1D01*
G01D02*
X435962Y980985D01*
G01X431778Y1000310D02*
Y990623D01*
G01D02*
G03X434284Y984573I8556J0D01*
G01D02*
X436917Y981940D01*
G01X429133Y1008860D02*
Y1001110D01*
G01D02*
G03X429533Y1000710I400J0D01*
G01D02*
X430028D01*
G01D02*
G02X430428Y1000310I0J-400D01*
G01X433073Y1008860D02*
Y1001110D01*
G01D02*
G02X432673Y1000710I-400J0D01*
G01D02*
X432178D01*
G01D02*
G03X431778Y1000310I0J-400D01*
G01X458071Y402953D02*
Y403035D01*
G01D02*
X456223Y404883D01*
G01X458071Y406890D02*
Y406935D01*
G01D02*
X456223Y408783D01*
G01X454134Y402953D02*
Y402972D01*
G01D02*
X452223Y404883D01*
G01X454134Y406890D02*
X454116D01*
G01D02*
X452223Y408783D01*
G01X450196Y402953D02*
X448227Y404922D01*
G01X450196Y406890D02*
X448227Y408859D01*
G01X455646Y418900D02*
G03X456856Y415979I4131J0D01*
G01D02*
X458071Y414764D01*
G01X447771Y420618D02*
G03X450196Y414764I8279J0D01*
G01X445705Y440784D02*
Y423910D01*
G01D02*
G03X445737Y423533I2199J-3D01*
G01D02*
G03X445873Y423067I2166J379D01*
G01D02*
X445903Y422995D01*
G01D02*
X446259Y422639D01*
G01D02*
Y422638D01*
G01X456789Y435058D02*
G03X455646Y432300I2758J-2759D01*
G01D02*
Y418900D01*
G01X463035Y439395D02*
X457647Y434007D01*
G01D02*
G03X456630Y432104I2623J-2625D01*
G01D02*
G03X456560Y431383I3641J-717D01*
G01D02*
Y421500D01*
G01D02*
G03X457057Y419812I3110J-1D01*
G01D02*
G03X457471Y419301I2610J1691D01*
G01D02*
X458071Y418701D01*
G01X462609Y432779D02*
G03X460470Y428345I5278J-5279D01*
G01D02*
G03X460423Y427499I7419J-836D01*
G01D02*
Y422604D01*
G01D02*
G03X460486Y422292I800J-1D01*
G01D02*
X462008Y418701D01*
G01X453865Y435500D02*
Y423287D01*
G01D02*
G03X454134Y422638I918J0D01*
G01X452515Y435501D02*
Y422769D01*
G01D02*
G03X452576Y422463I800J0D01*
G01D02*
X454134Y418701D01*
G01X449121Y438221D02*
Y427591D01*
G01D02*
G02X448905Y427070I-737J0D01*
G01D02*
G03X448685Y426539I531J-531D01*
G01D02*
Y421200D01*
G01D02*
G03X449384Y419514I2385J1D01*
G01D02*
X450196Y418701D01*
G01X447771Y438222D02*
Y420618D01*
G01X445055Y448900D02*
Y448024D01*
G01X445093Y442262D02*
G02X445705Y440784I-1479J-1478D01*
G01X461592Y439862D02*
X456842Y435112D01*
G01D02*
X456789Y435058D01*
G01X459055Y448900D02*
G02X458914Y448559I-483J0D01*
G01D02*
G03X458405Y447330I1229J-1229D01*
G01D02*
Y446099D01*
G01D02*
G02X456402Y441262I-6842J0D01*
G01D02*
X456145Y441005D01*
G01D02*
G03X453865Y435500I5506J-5505D01*
G01X456555Y448900D02*
G02X457055Y447693I-1207J-1207D01*
G01D02*
Y446100D01*
G01D02*
G02X455446Y442217I-5492J1D01*
G01D02*
X455447D01*
G01D02*
X455190Y441960D01*
G01D02*
G03X452515Y435501I6461J-6459D01*
G01X452055Y448900D02*
G03X451555Y447693I1207J-1207D01*
G01D02*
Y444097D01*
G01D02*
G02X450355Y441200I-4097J0D01*
G01D02*
G03X449121Y438221I2979J-2979D01*
G01X449555Y448900D02*
G02X450205Y447331I-1569J-1569D01*
G01D02*
Y444098D01*
G01D02*
G02X449400Y442155I-2747J0D01*
G01D02*
G03X447771Y438222I3934J-3933D01*
G01X444825Y451655D02*
G02X445055Y451100I-555J-555D01*
G01X458480Y762000D02*
Y452488D01*
G01D02*
G03X458896Y451484I1420J0D01*
G01D02*
G02X459055Y451100I-384J-384D01*
G01X457130Y762000D02*
Y452582D01*
G01D02*
G02X456843Y451887I-982J-1D01*
G01D02*
X456733Y451777D01*
G01D02*
G03X456555Y451349I426J-428D01*
G01D02*
Y451100D01*
G01X451480Y772005D02*
Y452488D01*
G01D02*
G03X451772Y451783I997J0D01*
G01D02*
G02X452055Y451100I-683J-683D01*
G01X450130Y772004D02*
Y452582D01*
G01D02*
G02X449843Y451888I-983J0D01*
G01D02*
X449732Y451777D01*
G01D02*
G03X449555Y451350I427J-427D01*
G01D02*
Y451100D01*
G01X460297Y766388D02*
G03X458480Y762000I4388J-4387D01*
G01X459342Y767343D02*
G03X457129Y762000I5343J-5343D01*
G01D02*
X457130D01*
G01X461505Y767595D02*
X460297Y766388D01*
G01X470700Y778700D02*
X460550Y768550D01*
G01D02*
X459342Y767343D01*
G01X447861Y780742D02*
G02X451480Y772005I-8738J-8738D01*
G01X446906Y779787D02*
G02X450130Y772004I-7783J-7783D01*
G01X458853Y830317D02*
Y802500D01*
G01D02*
G02X458453Y802100I-400J0D01*
G01D02*
X456278D01*
G01X460203Y830316D02*
Y802500D01*
G01D02*
G03X460603Y802100I400J0D01*
G01D02*
X462778D01*
G01X446785Y870162D02*
Y827072D01*
G01D02*
G02X445875Y824875I-3107J0D01*
G01X448135Y869726D02*
Y827072D01*
G01D02*
G02X446830Y823920I-4457J-1D01*
G01X463500Y841536D02*
G02X461000Y835500I-8536J0D01*
G01D02*
G03X458853Y830317I5183J-5183D01*
G01X461955Y834545D02*
G03X460203Y830316I4228J-4229D01*
G01X446828Y887344D02*
Y877262D01*
G01D02*
G02X446767Y876956I-800J0D01*
G01D02*
X446632Y876630D01*
G01D02*
G02X446134Y876174I-739J307D01*
G01D02*
X444886Y875779D01*
G01X448178Y877956D02*
G03X448904Y876203I2479J0D01*
G01D02*
G03X450247Y875750I1344J1766D01*
G01D02*
X450778D01*
G01X445262Y872016D02*
X446551Y870727D01*
G01D02*
G02X446785Y870162I-565J-565D01*
G01X450778Y872250D02*
X450659D01*
G01D02*
G03X450094Y872016I0J-799D01*
G01D02*
X448369Y870291D01*
G01D02*
G03X448135Y869726I565J-565D01*
G01X450778Y879250D02*
Y883000D01*
G01X446168Y999000D02*
Y889851D01*
G01D02*
G03X446428Y888537I3433J-3D01*
G01D02*
X446739Y887786D01*
G01D02*
X446740Y887785D01*
G01D02*
G02X446828Y887344I-1062J-441D01*
G01X447518Y928887D02*
Y889851D01*
G01D02*
G03X447676Y889054I2083J-1D01*
G01D02*
X447987Y888303D01*
G01D02*
G02X448178Y887345I-2309J-958D01*
G01D02*
Y877956D01*
G01X460778Y883000D02*
X462596Y881181D01*
G01X447518Y951998D02*
Y940007D01*
G01D02*
G03X447988Y939067I1140J-18D01*
G01D02*
G02X448458Y938127I-670J-922D01*
G01D02*
Y936927D01*
G01D02*
G02X447988Y935987I-1140J-18D01*
G01D02*
G03X447518Y935047I670J-922D01*
G01D02*
Y933847D01*
G01D02*
G03X447988Y932907I1140J-18D01*
G01D02*
G02X448458Y931967I-670J-922D01*
G01D02*
Y930767D01*
G01D02*
G02X447988Y929827I-1140J-18D01*
G01D02*
G03X447518Y928887I670J-922D01*
G01X448458Y960038D02*
G02X447988Y959098I-1140J-18D01*
G01D02*
G03X447518Y958158I670J-923D01*
G01D02*
Y956958D01*
G01D02*
G03X447988Y956018I1140J-18D01*
G01D02*
G02X448458Y955078I-670J-923D01*
G01D02*
Y953878D01*
G01D02*
G02X447988Y952938I-1140J-18D01*
G01D02*
G03X447518Y951998I670J-923D01*
G01X448458Y976798D02*
G02X447988Y975858I-1140J-18D01*
G01D02*
G03X447518Y974918I670J-923D01*
G01D02*
Y969278D01*
G01D02*
G03X447988Y968338I1140J-18D01*
G01D02*
G02X448458Y967398I-670J-923D01*
G01D02*
Y966198D01*
G01D02*
G02X447988Y965258I-1140J-18D01*
G01D02*
G03X447518Y964318I670J-923D01*
G01D02*
Y963118D01*
G01D02*
G03X447988Y962178I1140J-18D01*
G01D02*
G02X448458Y961238I-670J-923D01*
G01D02*
Y960038D01*
G01X447518Y998407D02*
Y986038D01*
G01D02*
G03X447988Y985098I1140J-18D01*
G01D02*
G02X448458Y984158I-670J-923D01*
G01D02*
Y982958D01*
G01D02*
G02X447988Y982018I-1140J-18D01*
G01D02*
G03X447518Y981078I670J-923D01*
G01D02*
Y979878D01*
G01D02*
G03X447988Y978938I1140J-18D01*
G01D02*
G02X448458Y977998I-670J-923D01*
G01D02*
Y976798D01*
G01X460628Y1008860D02*
Y1001998D01*
G01D02*
G03X461298Y1000380I2289J0D01*
G01X444883Y1008860D02*
Y1001657D01*
G01D02*
G03X445156Y1000687I1861J0D01*
G01D02*
G03X445428Y1000341I1589J969D01*
G01D02*
G03X445493Y1000186I220J1D01*
G01D02*
X445778Y999900D01*
G01D02*
X445807Y999870D01*
G01D02*
G02X446168Y999000I-870J-871D01*
G01X448818Y1008860D02*
Y1001545D01*
G01D02*
G02X448178Y1000000I-2185J0D01*
G01D02*
G03X447750Y999404I1592J-1595D01*
G01D02*
G03X447743Y999389I2038J-960D01*
G01D02*
G03X447708Y999314I2024J-990D01*
G01D02*
G03X447558Y998833I2063J-907D01*
G01D02*
G03X447547Y998774I2210J-442D01*
G01D02*
G03X447518Y998407I2225J-360D01*
G01X469305Y293800D02*
X467055Y296050D01*
G01D02*
Y306578D01*
G01X472805Y305500D02*
X476105Y302200D01*
G01D02*
X482200D01*
G01X467055Y306578D02*
X467077Y306600D01*
G01D02*
Y307077D01*
G01D02*
X470482Y310482D01*
G01D02*
Y315327D01*
G01D02*
X474673Y319518D01*
G01X476023Y323359D02*
Y318958D01*
G01D02*
X471832Y314767D01*
G01D02*
Y306473D01*
G01D02*
X472805Y305500D01*
G01X474673Y319518D02*
Y323358D01*
G01D02*
X473819Y324212D01*
G01Y328149D02*
X476055Y325913D01*
G01D02*
Y323391D01*
G01D02*
X476023Y323359D01*
G01X465945Y402953D02*
X467914Y404922D01*
G01X465945Y406890D02*
X467914Y408859D01*
G01X462008Y402953D02*
X463977Y404922D01*
G01X462008Y406890D02*
X463977Y408859D01*
G01X463515Y420631D02*
G03X465945Y414764I8297J0D01*
G01X479480Y440591D02*
G02X476810Y434145I-9117J0D01*
G01D02*
X473972Y431307D01*
G01D02*
G02X467556Y428650I-6416J6418D01*
G01D02*
X467071D01*
G01D02*
G03X465908Y428292I-1J-2066D01*
G01D02*
G03X465610Y428045I1164J-1707D01*
G01D02*
X465310Y427745D01*
G01D02*
G03X464434Y425978I2182J-2182D01*
G01D02*
Y420475D01*
G01D02*
G03X465085Y418903I2223J0D01*
G01D02*
G03X465573Y418701I488J488D01*
G01D02*
X465945D01*
G01X475855Y435100D02*
X473755Y433000D01*
G01D02*
X473017Y432263D01*
G01D02*
G02X467555Y430000I-5463J5462D01*
G01D02*
X467072D01*
G01D02*
G03X465149Y429409I-2J-3416D01*
G01D02*
G03X464655Y429000I1922J-2824D01*
G01D02*
G03X463515Y426248I2752J-2752D01*
G01D02*
Y420631D01*
G01X470792Y440963D02*
X462991Y433162D01*
G01D02*
X462992D01*
G01D02*
X462609Y432779D01*
G01X471748Y440008D02*
X463564Y431824D01*
G01D02*
G03X461812Y428193I4324J-4324D01*
G01D02*
X461773Y427507D01*
G01D02*
Y423166D01*
G01D02*
G03X462008Y422638I801J40D01*
G01X477555Y448900D02*
G02X478130Y447512I-1388J-1388D01*
G01Y440592D02*
G02X475855Y435100I-7767J0D01*
G01X463555Y448900D02*
Y448500D01*
G01D02*
G03X463838Y447817I966J0D01*
G01D02*
X463843Y447812D01*
G01D02*
G02X464130Y447118I-696J-694D01*
G01D02*
Y445300D01*
G01D02*
G02X462079Y440350I-7001J1D01*
G01D02*
X461592Y439862D01*
G01X466055Y448900D02*
Y448407D01*
G01D02*
G02X465767Y447712I-983J0D01*
G01D02*
G03X465480Y447018I696J-694D01*
G01D02*
Y445299D01*
G01D02*
G02X463035Y439395I-8351J0D01*
G01X470555Y448900D02*
G02X471130Y447512I-1388J-1388D01*
G01D02*
Y441776D01*
G01D02*
G02X470792Y440963I-1150J2D01*
G01X473055Y448900D02*
X472990D01*
G01D02*
G03X472618Y448651I0J-402D01*
G01D02*
X472538Y448459D01*
G01D02*
G03X472480Y448168I701J-291D01*
G01D02*
Y441776D01*
G01D02*
G02X471748Y440008I-2501J0D01*
G01X478130Y452488D02*
G02X477555Y451100I-1963J0D01*
G01X464130Y632449D02*
Y452488D01*
G01D02*
G02X463785Y451655I-1178J0D01*
G01D02*
G03X463555Y451100I555J-555D01*
G01X465480Y632448D02*
Y452488D01*
G01D02*
G03X465896Y451484I1420J0D01*
G01D02*
G02X466055Y451100I-384J-384D01*
G01X471130Y630261D02*
Y452488D01*
G01D02*
G02X470555Y451100I-1963J0D01*
G01X472480Y630261D02*
Y451859D01*
G01D02*
G03X472541Y451553I800J0D01*
G01D02*
X472626Y451347D01*
G01D02*
G03X472995Y451100I370J153D01*
G01D02*
X473055D01*
G01X473511Y636013D02*
G03X471129Y630261I5751J-5751D01*
G01D02*
X471130D01*
G01X474466Y635057D02*
G03X472480Y630261I4796J-4795D01*
G01X508510Y681510D02*
X467440Y640440D01*
G01D02*
G03X464130Y632449I7992J-7992D01*
G01X510229Y681319D02*
X468395Y639485D01*
G01D02*
G03X465480Y632448I7037J-7037D01*
G01X521379Y683879D02*
X474098Y636598D01*
G01D02*
X473511Y636013D01*
G01X522334Y682924D02*
X475052Y635642D01*
G01D02*
X474466Y635057D01*
G01X473178Y781422D02*
G02X471655Y777745I-5201J0D01*
G01D02*
X461505Y767595D01*
G01X471828Y781423D02*
G02X470700Y778700I-3851J0D01*
G01X473178Y806807D02*
Y781422D01*
G01X471828Y806831D02*
Y781423D01*
G01X469278Y805250D02*
Y802100D01*
G01X475778Y805250D02*
Y802100D01*
G01Y808750D02*
X475077D01*
G01D02*
G03X473797Y808301I0J-2049D01*
G01D02*
G03X473178Y806807I1494J-1494D01*
G01X469278Y808750D02*
X469823D01*
G01D02*
G02X471232Y808270I1J-2305D01*
G01D02*
G02X471828Y806831I-1439J-1439D01*
G01X471853Y833110D02*
Y814384D01*
G01D02*
G02X471619Y813819I-799J0D01*
G01D02*
X470285Y812484D01*
G01D02*
G02X469719Y812250I-565J566D01*
G01D02*
X469278D01*
G01X473203Y833109D02*
Y814729D01*
G01D02*
G03X473437Y814164I799J0D01*
G01D02*
X475115Y812485D01*
G01D02*
G03X475681Y812250I566J564D01*
G01D02*
X475778D01*
G01X463500Y879000D02*
Y841536D01*
G01X464850Y879786D02*
Y841537D01*
G01D02*
G02X461955Y834545I-9886J-2D01*
G01X476500Y869528D02*
Y844328D01*
G01D02*
G02X474500Y839500I-6828J0D01*
G01D02*
G03X471853Y833110I6390J-6390D01*
G01X477850Y844327D02*
G02X475455Y838545I-8178J1D01*
G01D02*
G03X473203Y833109I5435J-5436D01*
G01X476428Y877614D02*
G02X475791Y876076I-2175J0D01*
G01D02*
G02X474497Y875750I-1294J2405D01*
G01D02*
X473778D01*
G01Y872250D02*
G02X476500Y869528I0J-2722D01*
G01X473778Y879250D02*
Y883000D01*
G01X476428Y900900D02*
Y877614D01*
G01X462596Y881181D02*
G02X463500Y879000I-2181J-2182D01*
G01X467278Y883000D02*
X465406Y881128D01*
G01D02*
G03X464850Y879786I1342J-1342D01*
G01X465273Y915995D02*
X473642Y907626D01*
G01D02*
G02X476428Y900900I-6726J-6726D01*
G01X466228Y916950D02*
X474597Y908581D01*
G01D02*
G02X477778Y900900I-7681J-7680D01*
G01X461968Y998762D02*
Y923974D01*
G01D02*
G03X465273Y915995I11285J0D01*
G01X463318Y933305D02*
Y923975D01*
G01D02*
G03X466228Y916950I9935J0D01*
G01X463318Y944918D02*
Y938265D01*
G01D02*
G03X463788Y937325I1140J-18D01*
G01D02*
G02X464258Y936385I-670J-922D01*
G01D02*
Y935185D01*
G01D02*
G02X463788Y934245I-1140J-18D01*
G01D02*
G03X463318Y933305I670J-922D01*
G01X464258Y960318D02*
Y959118D01*
G01D02*
G02X463788Y958178I-1140J-18D01*
G01D02*
G03X463318Y957238I670J-922D01*
G01D02*
Y956038D01*
G01D02*
G03X463788Y955098I1140J-18D01*
G01D02*
G02X464258Y954158I-670J-922D01*
G01D02*
Y952958D01*
G01D02*
G02X463788Y952018I-1140J-18D01*
G01D02*
G03X463318Y951078I670J-922D01*
G01D02*
Y949878D01*
G01D02*
G03X463788Y948938I1140J-18D01*
G01D02*
G02X464258Y947998I-670J-922D01*
G01D02*
Y946798D01*
G01D02*
G02X463788Y945858I-1140J-18D01*
G01D02*
G03X463318Y944918I670J-922D01*
G01X464258Y976118D02*
G02X463788Y975178I-1140J-17D01*
G01D02*
G03X463318Y974238I670J-922D01*
G01D02*
Y962198D01*
G01D02*
G03X463788Y961258I1140J-18D01*
G01D02*
G02X464258Y960318I-670J-922D01*
G01X463318Y999056D02*
Y991518D01*
G01D02*
G03X463788Y990578I1140J-17D01*
G01D02*
G02X464258Y989638I-670J-922D01*
G01D02*
Y988438D01*
G01D02*
G02X463788Y987498I-1140J-17D01*
G01D02*
G03X463318Y986558I670J-922D01*
G01D02*
Y985358D01*
G01D02*
G03X463788Y984418I1140J-17D01*
G01D02*
G02X464258Y983478I-670J-922D01*
G01D02*
Y982278D01*
G01D02*
G02X463788Y981338I-1140J-17D01*
G01D02*
G03X463318Y980398I670J-922D01*
G01D02*
Y979198D01*
G01D02*
G03X463788Y978258I1140J-17D01*
G01D02*
G02X464258Y977318I-670J-922D01*
G01D02*
Y976118D01*
G01X461298Y1000380D02*
G02X461968Y998762I-1619J-1618D01*
G01X464568Y1008860D02*
Y1002074D01*
G01D02*
G02X463943Y1000565I-2134J0D01*
G01D02*
G03X463318Y999056I1509J-1509D01*
G01X476378Y1008860D02*
Y1002544D01*
G01D02*
G03X477328Y1000250I3244J0D01*
G01D02*
G02X478138Y998294I-1956J-1956D01*
G01X482200Y302200D02*
X484600Y304600D01*
G01D02*
X491840D01*
G01D02*
X494123Y306883D01*
G01X485630Y335870D02*
X487500Y334000D01*
G01D02*
Y333833D01*
G01X483662Y334054D02*
X483446D01*
G01D02*
X481693Y335807D01*
G01Y332086D02*
X483662Y330117D01*
G01X485630Y332086D02*
X487599Y330117D01*
G01X484000Y322000D02*
X484005D01*
G01D02*
G03X484850Y322350I0J1195D01*
G01D02*
X485200Y322700D01*
G01D02*
G03X485630Y323738I-1038J1038D01*
G01D02*
Y324212D01*
G01X487155Y321900D02*
X487214Y321959D01*
G01D02*
Y322041D01*
G01D02*
G02X486980Y322606I565J565D01*
G01D02*
Y323194D01*
G01D02*
G02X487214Y323759I799J0D01*
G01D02*
X487433Y323978D01*
G01D02*
G02X487998Y324212I565J-565D01*
G01D02*
X489567D01*
G01X485630Y328149D02*
X487599Y326180D01*
G01X481693Y328149D02*
X483662Y326180D01*
G01X495890Y348823D02*
G02X493504Y347834I-2387J2386D01*
G01X485630Y336023D02*
Y335870D01*
G01X481693Y335807D02*
Y336023D01*
G01X485630Y351771D02*
X487599Y349802D01*
G01X483662D02*
X483598D01*
G01D02*
X481693Y351707D01*
G01D02*
Y351771D01*
G01X485630Y347834D02*
X487599Y345865D01*
G01X481693Y347834D02*
X483662Y345865D01*
G01X487599Y341928D02*
X487272D01*
G01D02*
X485630Y343570D01*
G01D02*
Y343897D01*
G01X483662Y341928D02*
Y342033D01*
G01D02*
G03X483588Y342212I-253J0D01*
G01D02*
X482051Y343749D01*
G01D02*
G03X481693Y343897I-358J-359D01*
G01Y339960D02*
X483662Y337991D01*
G01X485630Y339960D02*
X487599Y337991D01*
G01X481693Y355708D02*
X483662Y353739D01*
G01X485630Y355708D02*
X487599Y353739D01*
G01X481693Y359645D02*
X483662Y357676D01*
G01X485630Y359645D02*
X487599Y357676D01*
G01X481693Y363582D02*
X481782D01*
G01D02*
X483663Y365463D01*
G01X485630Y363582D02*
Y363581D01*
G01D02*
X483662Y361613D01*
G01X481693Y367519D02*
X481799D01*
G01D02*
X483683Y369403D01*
G01X485630Y367519D02*
X485639D01*
G01D02*
X487603Y369483D01*
G01X495890Y356697D02*
G02X493504Y355708I-2387J2386D01*
G01X494491Y364570D02*
X493504Y363582D01*
G01X495890Y372445D02*
G02X493504Y371456I-2387J2386D01*
G01X480055Y448900D02*
X479959D01*
G01D02*
G03X479701Y448766I-1J-314D01*
G01D02*
X479600Y448621D01*
G01D02*
G03X479480Y448241I542J-380D01*
G01D02*
Y440591D01*
G01X478130Y447512D02*
Y440592D01*
G01X487666Y454924D02*
X514397Y428193D01*
G01X488621Y455879D02*
X515352Y429148D01*
G01X479480Y624606D02*
Y451959D01*
G01D02*
G03X479541Y451653I800J0D01*
G01D02*
X479668Y451347D01*
G01D02*
G03X480037Y451100I370J153D01*
G01D02*
X480055D01*
G01X478130Y624606D02*
Y452488D01*
G01X484880Y615462D02*
Y461650D01*
G01D02*
G03X487666Y454924I9513J0D01*
G01X486230Y615462D02*
Y461651D01*
G01D02*
G03X488621Y455879I8163J0D01*
G01X494000Y609683D02*
Y461284D01*
G01D02*
G03X495614Y457386I5512J-1D01*
G01X497405Y617905D02*
G03X494000Y609683I8222J-8221D01*
G01X528817Y676407D02*
X481222Y628812D01*
G01D02*
G03X479480Y624606I4206J-4206D01*
G01X527862Y677362D02*
X480267Y629767D01*
G01D02*
G03X478130Y624606I5161J-5160D01*
G01X533950Y668950D02*
X488003Y623003D01*
G01D02*
G03X484880Y615462I7541J-7540D01*
G01X534905Y667995D02*
X488958Y622048D01*
G01D02*
G03X486230Y615462I6586J-6586D01*
G01X477850Y871138D02*
Y844327D01*
G01X477778Y877551D02*
G03X478423Y875994I2202J0D01*
G01D02*
G03X479418Y875750I994J1904D01*
G01D02*
X480278D01*
G01Y872250D02*
X479811D01*
G01D02*
G03X478000Y871500I0J-2561D01*
G01D02*
G03X477850Y871138I362J-362D01*
G01X480278Y879250D02*
Y883000D01*
G01X477778Y900900D02*
Y877551D01*
G01X484728Y915950D02*
X495707Y904971D01*
G01X485683Y916905D02*
X496662Y905926D01*
G01X478138Y931860D02*
G03X484728Y915950I22501J0D01*
G01X479488Y931861D02*
G03X485683Y916905I21151J0D01*
G01X478138Y998294D02*
Y931860D01*
G01X479488Y946539D02*
Y939571D01*
G01D02*
G03X479958Y938631I1140J-18D01*
G01D02*
G02X480428Y937691I-670J-922D01*
G01D02*
Y936491D01*
G01D02*
G02X479958Y935551I-1140J-18D01*
G01D02*
G03X479488Y934611I670J-922D01*
G01D02*
Y931861D01*
G01X493328Y997872D02*
Y935799D01*
G01D02*
G03X506020Y905159I43333J1D01*
G01X479958Y959799D02*
G03X479488Y958859I670J-922D01*
G01D02*
Y957659D01*
G01D02*
G03X479958Y956719I1140J-18D01*
G01D02*
G02X480428Y955779I-670J-922D01*
G01D02*
Y954579D01*
G01D02*
G02X479958Y953639I-1140J-18D01*
G01D02*
G03X479488Y952699I670J-922D01*
G01D02*
Y951499D01*
G01D02*
G03X479958Y950559I1140J-18D01*
G01D02*
G02X480428Y949619I-670J-922D01*
G01D02*
Y948419D01*
G01D02*
G02X479958Y947479I-1140J-18D01*
G01D02*
G03X479488Y946539I670J-922D01*
G01X479958Y976438D02*
G03X479488Y975498I670J-923D01*
G01D02*
Y974298D01*
G01D02*
G03X479958Y973358I1140J-18D01*
G01D02*
G02X480428Y972418I-670J-923D01*
G01D02*
Y971218D01*
G01D02*
G02X479958Y970278I-1140J-18D01*
G01D02*
G03X479488Y969338I670J-923D01*
G01D02*
Y963819D01*
G01D02*
G03X479958Y962879I1140J-18D01*
G01D02*
G02X480428Y961939I-670J-922D01*
G01D02*
Y960739D01*
G01D02*
G02X479958Y959799I-1140J-18D01*
G01X479488Y1000079D02*
Y986618D01*
G01D02*
G03X479958Y985678I1140J-18D01*
G01D02*
G02X480428Y984738I-670J-923D01*
G01D02*
Y983538D01*
G01D02*
G02X479958Y982598I-1140J-18D01*
G01D02*
G03X479488Y981658I670J-923D01*
G01D02*
Y980458D01*
G01D02*
G03X479958Y979518I1140J-18D01*
G01D02*
G02X480428Y978578I-670J-923D01*
G01D02*
Y977378D01*
G01D02*
G02X479958Y976438I-1140J-18D01*
G01X480313Y1008860D02*
Y1001566D01*
G01D02*
G02X480079Y1001001I-799J0D01*
G01D02*
X479722Y1000644D01*
G01D02*
G03X479488Y1000079I565J-565D01*
G01X492128Y1008860D02*
Y1000769D01*
G01D02*
G03X492778Y999200I2219J0D01*
G01D02*
G02X493328Y997872I-1328J-1328D01*
G01X518000Y325650D02*
X507954D01*
G01D02*
G02X505617Y326618I0J3306D01*
G01D02*
X503895Y328340D01*
G01X518740Y327000D02*
X507955D01*
G01D02*
G02X506572Y327573I0J1956D01*
G01D02*
X504850Y329295D01*
G01X511505Y331151D02*
X508022Y334634D01*
G01D02*
G03X506455Y335283I-1567J-1567D01*
G01D02*
X503155D01*
G01D02*
G02X502769Y335312I-6J2505D01*
G01D02*
G02X501399Y336000I385J2475D01*
G01X510550Y330196D02*
X507067Y333679D01*
G01D02*
G03X506456Y333933I-613J-612D01*
G01D02*
X500753D01*
G01D02*
G02X498665Y334798I0J2953D01*
G01D02*
X498509Y334955D01*
G01D02*
X497441Y336023D01*
G01X511603Y334040D02*
X509888Y335755D01*
G01X515104Y323142D02*
X503091D01*
G01D02*
G02X500353Y324276I0J3873D01*
G01D02*
X499745Y324884D01*
G01D02*
X499216Y325412D01*
G01D02*
X499158Y325471D01*
G01D02*
X499111Y325516D01*
G01D02*
X498976Y325651D01*
G01D02*
X498928Y325700D01*
G01D02*
X498926Y325701D01*
G01D02*
X498120Y326510D01*
G01D02*
G02X497441Y328149I1639J1639D01*
G01X515105Y324492D02*
X503092D01*
G01D02*
G02X501308Y325231I0J2523D01*
G01D02*
X501044Y325496D01*
G01D02*
X500701Y325839D01*
G01D02*
G02X500555Y326192I354J353D01*
G01D02*
Y327293D01*
G01D02*
G02X500701Y327646I500J0D01*
G01D02*
X501081Y328026D01*
G01D02*
G02X501378Y328149I297J-297D01*
G01X498428Y352759D02*
X497441Y351771D01*
G01X503314Y353068D02*
G03X501666Y352059I1277J-3936D01*
G01D02*
X501378Y351771D01*
G01X511633Y344000D02*
G02X509700Y344800I-1J2733D01*
G01D02*
G03X508756Y345191I-944J-944D01*
G01D02*
X507169D01*
G01D02*
X506963Y345397D01*
G01D02*
X504592D01*
G01D02*
G03X504020Y345357I2J-4138D01*
G01D02*
G03X503314Y345194I574J-4098D01*
G01D02*
G03X501666Y344185I1277J-3936D01*
G01D02*
X501378Y343897D01*
G01X510655Y345755D02*
G03X508756Y346541I-1898J-1899D01*
G01D02*
X507169D01*
G01D02*
X506962Y346334D01*
G01D02*
X502890D01*
G01D02*
G03X501376Y345707I0J-2141D01*
G01D02*
G02X501154Y345615I-222J222D01*
G01D02*
X500192D01*
G01D02*
G03X498428Y344885I-1J-2494D01*
G01D02*
X497441Y343897D01*
G01X512205Y351378D02*
X505328D01*
G01D02*
G03X503155Y350478I0J-3073D01*
G01D02*
G02X502600Y350248I-555J555D01*
G01D02*
X497975D01*
G01D02*
G03X496850Y349782I0J-1591D01*
G01D02*
X495890Y348823D01*
G01X512204Y350028D02*
X505046D01*
G01D02*
G03X504310Y349723I0J-1041D01*
G01D02*
G02X503598Y349428I-712J712D01*
G01D02*
X500355D01*
G01D02*
G03X498101Y348495I-1J-3187D01*
G01D02*
X497441Y347834D01*
G01X501399Y336000D02*
G02X501384Y336016I1819J1720D01*
G01D02*
X501378Y336023D01*
G01X510844Y336710D02*
G03X508255Y337783I-2590J-2589D01*
G01D02*
X506638D01*
G01X509888Y335755D02*
G03X508255Y336433I-1635J-1633D01*
G01D02*
X506638D01*
G01X510901Y357902D02*
X505046D01*
G01D02*
G03X504310Y357597I0J-1041D01*
G01D02*
G02X503598Y357302I-712J712D01*
G01D02*
X500355D01*
G01D02*
G03X498101Y356369I-1J-3187D01*
G01D02*
X497441Y355708D01*
G01X510900Y359252D02*
X505328D01*
G01D02*
G03X503155Y358352I0J-3073D01*
G01D02*
G02X502600Y358122I-555J555D01*
G01D02*
X497975D01*
G01D02*
G03X496850Y357656I0J-1591D01*
G01D02*
X495890Y356697D01*
G01X510693Y354603D02*
X510546Y354457D01*
G01X510545Y354455D02*
G02X510449Y354415I-96J95D01*
G01D02*
X507169D01*
G01D02*
X506962Y354208D01*
G01D02*
X502890D01*
G01D02*
G03X501376Y353581I0J-2141D01*
G01D02*
G02X501154Y353489I-222J222D01*
G01D02*
X500192D01*
G01D02*
G03X498428Y352759I-1J-2494D01*
G01X511500Y353500D02*
G02X510450Y353065I-1050J1050D01*
G01D02*
X507169D01*
G01D02*
X506963Y353271D01*
G01D02*
X504592D01*
G01D02*
G03X503314Y353068I2J-4138D01*
G01X502209Y369500D02*
G03X499655Y368442I0J-3612D01*
G01D02*
X499645Y368432D01*
G01D02*
G02X497441Y367519I-2204J2204D01*
G01X508362Y369252D02*
G02X505700Y368150I-2661J2663D01*
G01D02*
X502901D01*
G01D02*
G03X502538Y368119I1J-2154D01*
G01D02*
G03X502124Y368005I362J-2123D01*
G01D02*
G03X501378Y367519I777J-2009D01*
G01X515700Y372700D02*
X510300Y367300D01*
G01D02*
G02X508446Y366532I-1854J1854D01*
G01D02*
X502930D01*
G01D02*
G03X502218Y366237I0J-1007D01*
G01D02*
G02X501692Y366019I-526J526D01*
G01D02*
X498953D01*
G01D02*
G03X497439Y365392I0J-2141D01*
G01D02*
G02X497217Y365300I-222J222D01*
G01D02*
X496255D01*
G01D02*
G03X494491Y364570I-1J-2494D01*
G01X511255Y366345D02*
G02X508447Y365182I-2808J2809D01*
G01D02*
X503073D01*
G01D02*
G03X502832Y365082I0J-341D01*
G01D02*
X500655D01*
G01D02*
G03X499377Y364879I2J-4138D01*
G01D02*
G03X497729Y363870I1277J-3936D01*
G01D02*
X497441Y363582D01*
G01X510850Y362350D02*
G02X509039Y361600I-1811J1811D01*
G01D02*
X502455D01*
G01D02*
X502405Y361650D01*
G01D02*
G03X501560Y362000I-845J-845D01*
G01D02*
X500380D01*
G01D02*
G03X498366Y361166I0J-2849D01*
G01D02*
X497862Y360662D01*
G01D02*
G03X497441Y359645I1018J-1017D01*
G01X511805Y361395D02*
G02X509039Y360250I-2765J2766D01*
G01D02*
X501983D01*
G01D02*
X501378Y359645D01*
G01X516051Y385961D02*
X505595Y375505D01*
G01D02*
X505181Y375090D01*
G01D02*
G02X504600Y374849I-581J581D01*
G01D02*
G03X502701Y374063I-1J-2685D01*
G01D02*
X502508Y373870D01*
G01D02*
X497975D01*
G01D02*
G03X496850Y373404I0J-1591D01*
G01D02*
X495890Y372445D01*
G01X517006Y385006D02*
X506551Y374551D01*
G01D02*
X506137Y374135D01*
G01D02*
G02X504600Y373499I-1536J1536D01*
G01D02*
G03X503656Y373108I0J-1335D01*
G01D02*
X503548Y373000D01*
G01D02*
X499074D01*
G01D02*
X498594Y372520D01*
G01D02*
G03X498101Y372117I1761J-2657D01*
G01D02*
X497441Y371456D01*
G01X522750Y385550D02*
X507407Y370207D01*
G01D02*
G02X505700Y369500I-1707J1707D01*
G01D02*
X502209D01*
G01X523705Y384595D02*
X508362Y369252D01*
G01X495614Y457386D02*
X520817Y432183D01*
G01X496569Y458341D02*
X521772Y433138D01*
G01X495350Y609683D02*
Y461284D01*
G01D02*
G03X496569Y458341I4162J0D01*
G01X500750Y591309D02*
Y465298D01*
G01D02*
G03X500937Y463819I5935J-1D01*
G01D02*
G03X502488Y461102I5748J1480D01*
G01D02*
X528021Y435569D01*
G01X502100Y591310D02*
Y465299D01*
G01D02*
G03X502245Y464156I4585J1D01*
G01D02*
G03X503443Y462057I4440J1143D01*
G01D02*
X528976Y436524D01*
G01X507500Y469480D02*
G03X509607Y464393I7195J0D01*
G01D02*
X534500Y439500D01*
G01X508850Y469481D02*
G03X510562Y465348I5845J0D01*
G01X507500Y586234D02*
Y469480D01*
G01X508850Y586234D02*
Y469481D01*
G01X564580Y657935D02*
X502724Y596079D01*
G01D02*
G03X500750Y591309I4769J-4767D01*
G01X566482Y657926D02*
X503679Y595124D01*
G01D02*
G03X502100Y591310I3814J-3813D01*
G01X510830Y594275D02*
G03X507500Y586234I8041J-8040D01*
G01X511785Y593320D02*
G03X508850Y586234I7086J-7086D01*
G01X498360Y616950D02*
G03X495350Y609683I7267J-7267D01*
G01X542849Y663349D02*
X497405Y617905D01*
G01X543806Y662396D02*
X498360Y616950D01*
G01X517970Y703269D02*
G02X509273Y682274I-29692J1D01*
G01D02*
X508510Y681510D01*
G01X519320Y703268D02*
G02X510229Y681319I-31042J0D01*
G01X495707Y904971D02*
X507986Y892693D01*
G01D02*
G02X517970Y868588I-24105J-24104D01*
G01X496662Y905926D02*
X508941Y893648D01*
G01D02*
G02X519321Y868588I-25060J-25060D01*
G01X506020Y905159D02*
X507728Y903450D01*
G01D02*
X517135Y894043D01*
G01X494678Y935800D02*
G03X506975Y906114I41983J1D01*
G01D02*
X507829Y905259D01*
G01D02*
X518090Y894998D01*
G01X509128Y999119D02*
Y923226D01*
G01D02*
G03X517351Y903374I28076J1D01*
G01X494678Y951498D02*
Y935800D01*
G01X495618Y959538D02*
G02X495148Y958598I-1140J-18D01*
G01D02*
G03X494678Y957658I670J-922D01*
G01D02*
Y956458D01*
G01D02*
G03X495148Y955518I1140J-18D01*
G01D02*
G02X495618Y954578I-670J-922D01*
G01D02*
Y953378D01*
G01D02*
G02X495148Y952438I-1140J-18D01*
G01D02*
G03X494678Y951498I670J-922D01*
G01X495148Y976687D02*
G03X494678Y975747I670J-922D01*
G01D02*
Y968778D01*
G01D02*
G03X495148Y967838I1140J-18D01*
G01D02*
G02X495618Y966898I-670J-922D01*
G01D02*
Y965698D01*
G01D02*
G02X495148Y964758I-1140J-18D01*
G01D02*
G03X494678Y963818I670J-922D01*
G01D02*
Y962618D01*
G01D02*
G03X495148Y961678I1140J-18D01*
G01D02*
G02X495618Y960738I-670J-922D01*
G01D02*
Y959538D01*
G01X494678Y993027D02*
G03X495148Y992087I1140J-18D01*
G01D02*
G02X495618Y991147I-670J-922D01*
G01D02*
Y989947D01*
G01D02*
G02X495148Y989007I-1140J-18D01*
G01D02*
G03X494678Y988067I670J-922D01*
G01D02*
Y986867D01*
G01D02*
G03X495148Y985927I1140J-18D01*
G01D02*
G02X495618Y984987I-670J-922D01*
G01D02*
Y983787D01*
G01D02*
G02X495148Y982847I-1140J-18D01*
G01D02*
G03X494678Y981907I670J-922D01*
G01D02*
Y980707D01*
G01D02*
G03X495148Y979767I1140J-18D01*
G01D02*
G02X495618Y978827I-670J-922D01*
G01D02*
Y977627D01*
G01D02*
G02X495148Y976687I-1140J-18D01*
G01X507873Y1008860D02*
Y1001036D01*
G01D02*
G03X508107Y1000471I799J0D01*
G01D02*
X508894Y999684D01*
G01D02*
G02X509089Y999362I-566J-563D01*
G01D02*
G02X509092Y999350I-771J-199D01*
G01D02*
G02X509128Y999119I-762J-237D01*
G01X496063Y1008860D02*
Y1001016D01*
G01D02*
G02X495829Y1000451I-799J0D01*
G01D02*
X494912Y999534D01*
G01D02*
G03X494678Y998969I565J-565D01*
G01D02*
Y993027D01*
G01X524383Y320394D02*
X523348Y319359D01*
G01X516283Y318377D02*
Y317177D01*
G01D02*
G03X516683Y316777I400J0D01*
G01D02*
X516708D01*
G01D02*
G02X517108Y316377I0J-400D01*
G01D02*
Y315000D01*
G01D02*
X516283Y314175D01*
G01D02*
G02X515860Y314000I-423J424D01*
G01X519283Y318377D02*
Y317177D01*
G01D02*
G02X518883Y316777I-400J0D01*
G01D02*
X518858D01*
G01D02*
G03X518458Y316377I0J-400D01*
G01D02*
Y315000D01*
G01D02*
G03X519458Y314000I1000J0D01*
G01D02*
X519706D01*
G01X521623Y324783D02*
X522740D01*
G01D02*
G03X523023Y324900I0J401D01*
G01D02*
X523364Y325241D01*
G01D02*
G02X523647Y325358I283J-284D01*
G01D02*
X524120D01*
G01D02*
G02X524500Y324978I0J-380D01*
G01D02*
Y320677D01*
G01D02*
G02X524383Y320394I-401J0D01*
G01X519423Y324783D02*
X518949Y325257D01*
G01D02*
G03X518000Y325650I-949J-949D01*
G01X519423Y327283D02*
G02X518740Y327000I-683J683D01*
G01X521623Y327283D02*
X522740D01*
G01D02*
G02X523023Y327166I0J-401D01*
G01D02*
X523364Y326825D01*
G01D02*
G03X523647Y326708I283J284D01*
G01D02*
X524120D01*
G01D02*
G02X525850Y324978I0J-1730D01*
G01D02*
Y320677D01*
G01D02*
G03X525967Y320394I401J0D01*
G01D02*
X527002Y319359D01*
G01X525423Y332783D02*
G02X523533Y332000I-1890J1890D01*
G01D02*
X521504D01*
G01D02*
G03X520055Y331400I0J-2049D01*
G01D02*
G02X518384Y330708I-1671J1671D01*
G01D02*
X512574D01*
G01D02*
G02X511505Y331151I0J1512D01*
G01X525423Y330283D02*
G03X524537Y330650I-886J-886D01*
G01D02*
X521503D01*
G01D02*
G03X521010Y330445I1J-699D01*
G01D02*
G02X518384Y329358I-2625J2626D01*
G01D02*
X512573D01*
G01D02*
G02X510550Y330196I1J2862D01*
G01X517123Y334783D02*
X518240D01*
G01D02*
G02X518523Y334666I0J-401D01*
G01D02*
X518864Y334325D01*
G01D02*
G03X519147Y334208I283J284D01*
G01D02*
X519620D01*
G01D02*
G03X521230Y334875I0J2277D01*
G01D02*
X521555Y335200D01*
G01D02*
G02X523004Y335800I1449J-1449D01*
G01X514923Y334783D02*
G02X514240Y334500I-683J683D01*
G01D02*
X513755D01*
G01D02*
G02X512558Y334995I-1J1692D01*
G01D02*
X510844Y336710D01*
G01X514923Y332283D02*
X514162Y333044D01*
G01D02*
G03X513906Y333150I-256J-256D01*
G01D02*
X513756D01*
G01D02*
G02X511603Y334040I-3J3042D01*
G01X517123Y332283D02*
X518240D01*
G01D02*
G03X518523Y332400I0J401D01*
G01D02*
X518864Y332741D01*
G01D02*
G02X519147Y332858I283J-284D01*
G01D02*
X519620D01*
G01D02*
G03X522185Y333920I1J3627D01*
G01D02*
X522510Y334245D01*
G01D02*
G02X523004Y334450I494J-494D01*
G01D02*
X532238D01*
G01X516283Y320577D02*
X516854Y321149D01*
G01D02*
G03X517000Y321500I-351J352D01*
G01D02*
G03X516583Y322507I-1424J0D01*
G01D02*
X516545Y322545D01*
G01D02*
G03X515104Y323142I-1441J-1441D01*
G01X519283Y320577D02*
G02X518350Y321510I0J933D01*
G01D02*
G03X517538Y323462I-2775J-9D01*
G01D02*
X517500Y323500D01*
G01D02*
G03X515105Y324492I-2395J-2396D01*
G01X515900Y343500D02*
G03X514693Y344000I-1207J-1207D01*
G01D02*
X511633D01*
G01X518100Y343500D02*
X519217D01*
G01D02*
G03X519500Y343617I0J401D01*
G01D02*
X519841Y343958D01*
G01D02*
G02X520124Y344075I283J-284D01*
G01D02*
X525197D01*
G01D02*
G02X525533Y343936I0J-476D01*
G01D02*
X526500Y342969D01*
G01X518100Y346000D02*
X519217D01*
G01D02*
G02X519500Y345883I0J-401D01*
G01D02*
X519841Y345542D01*
G01D02*
G03X520124Y345425I283J284D01*
G01D02*
X525000D01*
G01D02*
G03X525671Y345703I0J949D01*
G01D02*
X526500Y346532D01*
G01X515900Y346000D02*
G02X514331Y345350I-1569J1569D01*
G01D02*
X511633D01*
G01D02*
G02X510655Y345755I0J1383D01*
G01X515900Y351000D02*
X515498Y350597D01*
G01D02*
G02X514900Y350350I-597J598D01*
G01D02*
X514400D01*
G01D02*
G02X513802Y350597I-1J845D01*
G01D02*
X513600Y350800D01*
G01D02*
G03X512205Y351378I-1395J-1395D01*
G01X518100Y351000D02*
X519293D01*
G01D02*
G03X520500Y351500I0J1707D01*
G01X518100Y348500D02*
X519141D01*
G01D02*
G02X520500Y347937I0J-1922D01*
G01X515900Y348500D02*
X515753Y348646D01*
G01D02*
G03X514900Y349000I-854J-853D01*
G01D02*
X514400D01*
G01D02*
Y348999D01*
G01D02*
G02X512846Y349643I0J2196D01*
G01D02*
X512644Y349845D01*
G01D02*
G03X512204Y350028I-441J-439D01*
G01X523004Y335800D02*
X532239D01*
G01X515900Y359500D02*
G03X515538Y359650I-362J-362D01*
G01D02*
X514999D01*
G01D02*
G03X513907Y359196I3J-1546D01*
G01D02*
X513848Y359138D01*
G01D02*
X513814Y359104D01*
G01D02*
G02X510901Y357902I-2913J2929D01*
G01X518100Y359500D02*
X519141D01*
G01D02*
G02X520500Y358937I0J-1922D01*
G01X518100Y362000D02*
X519293D01*
G01D02*
G03X520500Y362500I0J1707D01*
G01X515900Y362000D02*
Y361900D01*
G01D02*
G02X515000Y361000I-900J0D01*
G01D02*
G03X512952Y360152I0J-2897D01*
G01D02*
X512900Y360100D01*
G01D02*
X512866Y360067D01*
G01D02*
G02X510900Y359252I-1967J1966D01*
G01X515900Y356000D02*
X515639Y355739D01*
G01D02*
G02X514700Y355350I-939J939D01*
G01D02*
X512499D01*
G01D02*
G03X510693Y354603I0J-2557D01*
G01X510546Y354457D02*
X510545Y354455D01*
G01X518100Y356000D02*
X519217D01*
G01D02*
G02X519500Y355883I0J-401D01*
G01D02*
X519841Y355542D01*
G01D02*
G03X520124Y355425I283J284D01*
G01D02*
X525227D01*
G01D02*
G03X525510Y355542I0J401D01*
G01D02*
X526500Y356532D01*
G01X518100Y353500D02*
X519217D01*
G01D02*
G03X519500Y353617I0J401D01*
G01D02*
X519841Y353958D01*
G01D02*
G02X520124Y354075I283J-284D01*
G01D02*
X525228D01*
G01D02*
G02X525511Y353958I0J-401D01*
G01D02*
X526500Y352969D01*
G01X515900Y353500D02*
X515895Y353505D01*
G01D02*
G03X514700Y354000I-1195J-1195D01*
G01D02*
X512500D01*
G01D02*
G03X511647Y353646I1J-1207D01*
G01D02*
X511500Y353500D01*
G01X516681Y371771D02*
X511255Y366345D01*
G01X518835Y368850D02*
G03X516300Y367800I0J-3585D01*
G01D02*
X510850Y362350D01*
G01X537592Y382407D02*
X523792Y368607D01*
G01D02*
G02X521118Y367500I-2673J2674D01*
G01D02*
X518835D01*
G01D02*
G03X517255Y366845I1J-2235D01*
G01D02*
X511805Y361395D01*
G01X524405Y386285D02*
G02X523705Y384595I-2391J0D01*
G01X529850Y385050D02*
X519549Y374749D01*
G01D02*
X518799Y373998D01*
G01D02*
G02X518200Y373751I-598J600D01*
G01D02*
G03X516622Y373375I0J-3500D01*
G01D02*
G03X515726Y372727I1577J-3124D01*
G01D02*
X515700Y372700D01*
G01X530805Y384095D02*
X520505Y373795D01*
G01D02*
X519754Y373043D01*
G01D02*
G02X518200Y372400I-1553J1554D01*
G01D02*
G03X516681Y371771I0J-2149D01*
G01X536637Y383362D02*
X522837Y369562D01*
G01D02*
G02X521118Y368850I-1719J1719D01*
G01D02*
X518835D01*
G01X515865Y388360D02*
G02X516455Y386936I-1424J-1424D01*
G01D02*
G02X516051Y385961I-1379J0D01*
G01X516355Y423466D02*
Y391743D01*
G01D02*
G02X515865Y390560I-1673J0D01*
G01X517705Y423467D02*
Y392100D01*
G01D02*
G03X518327Y390597I2125J-1D01*
G01D02*
X518365Y390560D01*
G01Y388360D02*
G03X517805Y387008I1352J-1352D01*
G01D02*
Y386936D01*
G01D02*
G02X517006Y385006I-2729J-1D01*
G01X522555Y387900D02*
G02X523055Y386693I-1207J-1207D01*
G01D02*
Y386286D01*
G01D02*
G02X522750Y385550I-1041J0D01*
G01X523130Y426601D02*
Y392124D01*
G01D02*
G02X523013Y391841I-401J0D01*
G01D02*
X522672Y391500D01*
G01D02*
G03X522555Y391217I284J-283D01*
G01D02*
Y390100D01*
G01X524480Y426600D02*
Y392124D01*
G01D02*
G03X524597Y391841I401J0D01*
G01D02*
X524938Y391500D01*
G01D02*
G02X525055Y391217I-284J-283D01*
G01D02*
Y390100D01*
G01Y387900D02*
X524847Y387692D01*
G01D02*
G03X524405Y386625I1067J-1067D01*
G01D02*
Y386285D01*
G01X514397Y428193D02*
G02X516355Y423466I-4727J-4727D01*
G01X515352Y429148D02*
G02X517705Y423467I-5682J-5681D01*
G01X520817Y432183D02*
G02X523129Y426600I-5583J-5582D01*
G01D02*
X523130Y426601D01*
G01X521772Y433138D02*
G02X524480Y426600I-6538J-6538D01*
G01X510562Y465348D02*
X535455Y440455D01*
G01X547555Y631000D02*
X510830Y594275D01*
G01X548510Y630045D02*
X511785Y593320D01*
G01X526056Y872506D02*
Y695170D01*
G01D02*
G02X521379Y683879I-15968J0D01*
G01X527406Y695169D02*
G02X522334Y682924I-17318J0D01*
G01X517970Y868588D02*
Y703269D01*
G01X519320Y868588D02*
Y703268D01*
G01X519321Y868588D02*
X519320D01*
G01X517135Y894043D02*
G02X526056Y872506I-21537J-21537D01*
G01X518090Y894998D02*
G02X527406Y872507I-22492J-22491D01*
G01X510478Y923227D02*
G03X518306Y904329I26726J0D01*
G01D02*
X527064Y895571D01*
G01X517351Y903374D02*
X526109Y894616D01*
G01D02*
G02X532917Y878180I-16436J-16436D01*
G01X524828Y910594D02*
G03X527622Y903847I9542J-1D01*
G01X526178Y910594D02*
G03X528577Y904802I8191J0D01*
G01X510478Y950756D02*
Y923227D01*
G01X524828Y999055D02*
Y910594D01*
G01X526178Y938383D02*
Y910594D01*
G01Y943343D02*
G03X526648Y942403I1140J-18D01*
G01D02*
G02X527118Y941463I-670J-922D01*
G01Y940263D02*
G02X526648Y939323I-1140J-18D01*
G01D02*
G03X526178Y938383I670J-922D01*
G01X511418Y959996D02*
Y958796D01*
G01D02*
G02X510948Y957856I-1140J-18D01*
G01D02*
G03X510478Y956916I670J-922D01*
G01D02*
Y955716D01*
G01D02*
G03X510948Y954776I1140J-18D01*
G01D02*
G02X511418Y953836I-670J-922D01*
G01D02*
Y952636D01*
G01D02*
G02X510948Y951696I-1140J-18D01*
G01D02*
G03X510478Y950756I670J-922D01*
G01X526178Y998834D02*
Y955663D01*
G01D02*
G03X526648Y954723I1140J-18D01*
G01D02*
G02X527118Y953783I-670J-922D01*
G01Y952583D02*
G02X526648Y951643I-1140J-18D01*
G01D02*
G03X526178Y950703I670J-922D01*
G01D02*
Y949503D01*
G01D02*
G03X526648Y948563I1140J-18D01*
G01D02*
G02X527118Y947623I-670J-922D01*
G01Y946423D02*
G02X526648Y945483I-1140J-18D01*
G01D02*
G03X526178Y944543I670J-922D01*
G01D02*
Y943343D01*
G01X510948Y976638D02*
G03X510478Y975698I670J-922D01*
G01D02*
Y968036D01*
G01D02*
G03X510948Y967096I1140J-18D01*
G01D02*
G02X511418Y966156I-670J-922D01*
G01D02*
Y964956D01*
G01D02*
G02X510948Y964016I-1140J-18D01*
G01D02*
G03X510478Y963076I670J-922D01*
G01D02*
Y961876D01*
G01D02*
G03X510948Y960936I1140J-18D01*
G01D02*
G02X511418Y959996I-670J-922D01*
G01X510478Y999069D02*
Y986818D01*
G01D02*
G03X510948Y985878I1140J-17D01*
G01D02*
G02X511418Y984938I-670J-922D01*
G01D02*
Y983738D01*
G01D02*
G02X510948Y982798I-1140J-17D01*
G01D02*
G03X510478Y981858I670J-922D01*
G01D02*
Y980658D01*
G01D02*
G03X510948Y979718I1140J-17D01*
G01D02*
G02X511418Y978778I-670J-922D01*
G01D02*
Y977578D01*
G01D02*
G02X510948Y976638I-1140J-17D01*
G01X511813Y1008860D02*
Y1000611D01*
G01D02*
G02X511780Y1000447I-429J1D01*
G01D02*
X511745Y1000362D01*
G01D02*
G02X511515Y1000131I-394J162D01*
G01D02*
X511143Y999978D01*
G01D02*
G03X510884Y999805I306J-739D01*
G01D02*
X510712Y999634D01*
G01D02*
G03X510478Y999069I565J-565D01*
G01X523623Y1008860D02*
Y1001600D01*
G01D02*
G03X524221Y1000158I2040J1D01*
G01D02*
X524478Y999900D01*
G01D02*
G02X524692Y999607I-847J-843D01*
G01D02*
G02X524787Y999362I-1059J-552D01*
G01D02*
G02X524828Y999055I-1153J-310D01*
G01X527137Y1000031D02*
X526578Y999800D01*
G01D02*
G03X526178Y998834I966J-966D01*
G01X527623Y332783D02*
X528740D01*
G01D02*
G02X529023Y332666I0J-401D01*
G01D02*
X529364Y332325D01*
G01D02*
G03X529647Y332208I283J284D01*
G01D02*
X530120D01*
G01D02*
G02X532350Y329978I0J-2230D01*
G01D02*
Y326818D01*
G01D02*
G03X532467Y326535I401J0D01*
G01D02*
X533502Y325500D01*
G01X527623Y330283D02*
X528740D01*
G01D02*
G03X529023Y330400I0J401D01*
G01D02*
X529364Y330741D01*
G01D02*
G02X529647Y330858I283J-284D01*
G01D02*
X530120D01*
G01D02*
G02X531000Y329978I0J-880D01*
G01D02*
Y326818D01*
G01D02*
G02X530883Y326535I-401J0D01*
G01D02*
X529848Y325500D01*
G01X532239Y335800D02*
G02X534757Y334757I0J-3562D01*
G01D02*
X536377Y333137D01*
G01D02*
G02X537462Y330516I-2621J-2620D01*
G01D02*
Y323000D01*
G01D02*
G03X538062Y321553I2047J1D01*
G01D02*
X538614Y321000D01*
G01X532238Y334450D02*
G02X533802Y333802I0J-2212D01*
G01D02*
X535422Y332182D01*
G01D02*
G02X536112Y330516I-1666J-1666D01*
G01D02*
Y323000D01*
G01D02*
G02X535512Y321553I-2047J1D01*
G01D02*
X534960Y321000D01*
G01X531505Y385786D02*
G02X530805Y384095I-2391J-1D01*
G01X537075Y385876D02*
Y384419D01*
G01D02*
G02X536637Y383362I-1495J0D01*
G01X538425Y385876D02*
Y384418D01*
G01D02*
G02X537592Y382407I-2845J1D01*
G01X529555Y387900D02*
G02X530155Y386451I-1449J-1449D01*
G01D02*
Y385786D01*
G01D02*
G02X529850Y385050I-1041J0D01*
G01X530155Y430417D02*
Y391549D01*
G01D02*
G02X529555Y390100I-2049J0D01*
G01X531505Y430417D02*
Y391428D01*
G01D02*
G03X532055Y390100I1878J0D01*
G01Y387900D02*
G03X531505Y386572I1328J-1328D01*
G01D02*
Y385786D01*
G01X536500Y387900D02*
Y386783D01*
G01D02*
G03X536617Y386500I401J0D01*
G01D02*
X536958Y386159D01*
G01D02*
G02X537075Y385876I-284J-283D01*
G01Y433284D02*
Y392124D01*
G01D02*
G02X536958Y391841I-401J0D01*
G01D02*
X536617Y391500D01*
G01D02*
G03X536500Y391217I284J-283D01*
G01D02*
Y390100D01*
G01X538425Y433285D02*
Y392124D01*
G01D02*
G03X538542Y391841I401J0D01*
G01D02*
X538883Y391500D01*
G01D02*
G02X539000Y391217I-284J-283D01*
G01D02*
Y390100D01*
G01Y387900D02*
Y386783D01*
G01D02*
G02X538883Y386500I-401J0D01*
G01D02*
X538542Y386159D01*
G01D02*
G03X538425Y385876I284J-283D01*
G01X528021Y435569D02*
G02X530155Y430417I-5152J-5152D01*
G01X528976Y436524D02*
G02X531505Y430417I-6107J-6106D01*
G01X534500Y439500D02*
G02X537075Y433284I-6215J-6216D01*
G01X535455Y440455D02*
G02X538425Y433285I-7170J-7170D01*
G01X552500Y686259D02*
G02X543124Y663625I-32010J1D01*
G01D02*
X542849Y663349D01*
G01X534267Y689566D02*
G02X528817Y676407I-18609J-1D01*
G01X532917Y689566D02*
G02X527862Y677362I-17259J0D01*
G01X540084Y683759D02*
G02X533950Y668950I-20943J0D01*
G01X541434Y683759D02*
G02X534905Y667995I-22294J-1D01*
G01X534267Y878180D02*
Y689566D01*
G01X532917Y878180D02*
Y689566D01*
G01X527406Y872507D02*
Y695169D01*
G01X540084Y887237D02*
Y683759D01*
G01X541434Y887238D02*
Y683759D01*
G01X527064Y895571D02*
G02X534267Y878180I-17391J-17390D01*
G01X537151Y894318D02*
G02X540084Y887237I-7081J-7081D01*
G01X538106Y895273D02*
G02X541434Y887238I-8036J-8035D01*
G01X527622Y903847D02*
X537151Y894318D01*
G01X528577Y904802D02*
X538106Y895273D01*
G01X540339Y999301D02*
Y909062D01*
G01D02*
G03X542679Y903411I7991J-1D01*
G01D02*
X549067Y897023D01*
G01X541689Y949886D02*
Y909062D01*
G01D02*
G03X543634Y904366I6641J0D01*
G01X527118Y941463D02*
Y940263D01*
G01Y953783D02*
Y952583D01*
G01Y947623D02*
Y946423D01*
G01X542159Y960066D02*
G02X542629Y959126I-670J-922D01*
G01D02*
Y957926D01*
G01D02*
G02X542159Y956986I-1140J-18D01*
G01D02*
G03X541689Y956046I670J-922D01*
G01D02*
Y954846D01*
G01D02*
G03X542159Y953906I1140J-18D01*
G01D02*
G02X542629Y952966I-670J-922D01*
G01D02*
Y951766D01*
G01D02*
G02X542159Y950826I-1140J-18D01*
G01D02*
G03X541689Y949886I670J-922D01*
G01Y998970D02*
Y967166D01*
G01D02*
G03X542159Y966226I1140J-18D01*
G01D02*
G02X542629Y965286I-670J-922D01*
G01D02*
Y964086D01*
G01D02*
G02X542159Y963146I-1140J-18D01*
G01D02*
G03X541689Y962206I670J-922D01*
G01D02*
Y961006D01*
G01D02*
G03X542159Y960066I1140J-18D01*
G01X527558Y1008860D02*
Y1000795D01*
G01D02*
G02X527422Y1000229I-1243J-1D01*
G01D02*
X527400Y1000206D01*
G01D02*
G02X527137Y1000031I-566J565D01*
G01X539368Y1008860D02*
Y1000960D01*
G01D02*
G03X539618Y1000358I852J1D01*
G01D02*
X539667Y1000308D01*
G01D02*
X540102Y999873D01*
G01D02*
G02X540244Y999680I-573J-570D01*
G01D02*
G02X540339Y999301I-713J-380D01*
G01X543308Y1001309D02*
G02X542957Y1000463I-1197J1D01*
G01D02*
X541848Y999354D01*
G01D02*
G03X541689Y998970I384J-384D01*
G01X549505Y632949D02*
X547555Y631000D01*
G01X550460Y631994D02*
X548510Y630045D01*
G01X574603Y658047D02*
X549505Y632949D01*
G01X575558Y657092D02*
X550460Y631994D01*
G01X553850Y686258D02*
G02X544080Y662671I-33360J1D01*
G01D02*
X543806Y662396D01*
G01X552500Y888735D02*
Y686259D01*
G01X553850Y888735D02*
Y686258D01*
G01X549067Y897023D02*
G02X552500Y888735I-8288J-8288D01*
G01X550022Y897978D02*
G02X553850Y888735I-9243J-9242D01*
G01X543634Y904366D02*
X550022Y897978D01*
G01X543308Y1008860D02*
Y1001309D01*
G01X568814Y666818D02*
G02X565527Y658881I-11224J-1D01*
G01D02*
X564580Y657935D01*
G01X570164Y666818D02*
G02X568761Y661044I-12575J-2D01*
G01D02*
G02X566482Y657926I-11171J5773D01*
G01X580078Y671265D02*
G02X574603Y658047I-18693J0D01*
G01X581428Y671265D02*
G02X575558Y657092I-20043J-1D01*
G01X568814Y912091D02*
Y666818D01*
G01X570164Y912121D02*
Y666818D01*
G01X564628Y998819D02*
Y921936D01*
G01D02*
G03X566493Y917433I6368J0D01*
G01D02*
X566678Y917248D01*
G01D02*
G02X568814Y912091I-5157J-5157D01*
G01X565978Y948872D02*
Y921935D01*
G01D02*
X565979Y921936D01*
G01D02*
G03X567448Y918388I5018J-1D01*
G01D02*
X567633Y918203D01*
G01D02*
G02X570156Y912478I-6112J-6112D01*
G01D02*
G02X570164Y912121I-7970J-357D01*
G01X565978Y959992D02*
G03X566448Y959052I1140J-18D01*
G01D02*
G02X566918Y958112I-670J-923D01*
G01D02*
Y956912D01*
G01D02*
G02X566448Y955972I-1140J-18D01*
G01D02*
G03X565978Y955032I670J-923D01*
G01D02*
Y953832D01*
G01D02*
G03X566448Y952892I1140J-18D01*
G01D02*
G02X566918Y951952I-670J-923D01*
G01D02*
Y950752D01*
G01D02*
G02X566448Y949812I-1140J-18D01*
G01D02*
G03X565978Y948872I670J-923D01*
G01Y979069D02*
Y966152D01*
G01D02*
G03X566448Y965212I1140J-18D01*
G01D02*
G02X566918Y964272I-670J-923D01*
G01D02*
Y963072D01*
G01D02*
G02X566448Y962132I-1140J-18D01*
G01D02*
G03X565978Y961192I670J-923D01*
G01D02*
Y959992D01*
G01Y998764D02*
Y990189D01*
G01D02*
G03X566448Y989249I1140J-18D01*
G01D02*
G02X566918Y988309I-670J-923D01*
G01D02*
Y987109D01*
G01D02*
G02X566448Y986169I-1140J-18D01*
G01D02*
G03X565978Y985229I670J-923D01*
G01D02*
Y984029D01*
G01D02*
G03X566448Y983089I1140J-18D01*
G01D02*
G02X566918Y982149I-670J-923D01*
G01D02*
Y980949D01*
G01D02*
G02X566448Y980009I-1140J-18D01*
G01D02*
G03X565978Y979069I670J-923D01*
G01X562993Y1008860D02*
Y1000247D01*
G01D02*
G03X563178Y999800I632J0D01*
G01D02*
G03X563419Y999700I241J241D01*
G01D02*
X563845D01*
G01D02*
G02X564291Y999499I-1J-597D01*
G01D02*
X564442Y999330D01*
G01D02*
G02X564628Y998819I-613J-512D01*
G01X566928Y1008860D02*
Y1001057D01*
G01D02*
G02X566428Y999850I-1707J0D01*
G01D02*
G03X566151Y999472I1086J-1086D01*
G01D02*
G03X566016Y999106I1362J-710D01*
G01D02*
G03X565978Y998764I1498J-340D01*
G01X580078Y998669D02*
Y671265D01*
G01X581428Y946927D02*
Y671265D01*
G01X581898Y960187D02*
G03X581428Y959247I670J-922D01*
G01D02*
Y958047D01*
G01D02*
G03X581898Y957107I1140J-18D01*
G01D02*
G02X582368Y956167I-670J-922D01*
G01D02*
Y954967D01*
G01D02*
G02X581898Y954027I-1140J-18D01*
G01D02*
G03X581428Y953087I670J-922D01*
G01D02*
Y951887D01*
G01D02*
G03X581898Y950947I1140J-18D01*
G01D02*
G02X582368Y950007I-670J-922D01*
G01D02*
Y948807D01*
G01D02*
G02X581898Y947867I-1140J-18D01*
G01D02*
G03X581428Y946927I670J-922D01*
G01X582368Y976143D02*
G02X581898Y975203I-1140J-18D01*
G01D02*
G03X581428Y974263I670J-922D01*
G01D02*
Y964207D01*
G01D02*
G03X581898Y963267I1140J-18D01*
G01D02*
G02X582368Y962327I-670J-922D01*
G01D02*
Y961127D01*
G01D02*
G02X581898Y960187I-1140J-18D01*
G01X581428Y998472D02*
Y985383D01*
G01D02*
G03X581898Y984443I1140J-18D01*
G01D02*
G02X582368Y983503I-670J-922D01*
G01D02*
Y982303D01*
G01D02*
G02X581898Y981363I-1140J-18D01*
G01D02*
G03X581428Y980423I670J-922D01*
G01D02*
Y979223D01*
G01D02*
G03X581898Y978283I1140J-18D01*
G01D02*
G02X582368Y977343I-670J-922D01*
G01D02*
Y976143D01*
G01X578738Y1008860D02*
Y1000671D01*
G01D02*
G03X578972Y1000106I799J0D01*
G01D02*
X579844Y999234D01*
G01D02*
G02X580078Y998669I-565J-565D01*
G01X582678Y1008860D02*
Y1001490D01*
G01D02*
G02X581978Y999800I-2390J0D01*
G01D02*
G03X581428Y998472I1328J-1328D01*
G01X1092400Y92600D02*
Y87700D01*
G01X1091750Y93250D02*
X1092400Y92600D01*
G01X1140544Y778485D02*
X1140558D01*
G01D02*
X1142323Y780250D01*
G01X1143693Y778485D02*
Y779215D01*
G01D02*
X1144023Y779545D01*
G01D02*
Y780955D01*
G01D02*
X1143470Y781508D01*
G01D02*
Y782805D01*
G01X1149992Y791083D02*
X1151392Y789683D01*
G01X1152893Y722205D02*
Y723445D01*
G01D02*
X1154300Y724852D01*
G01D02*
Y728352D01*
G01D02*
X1152248Y730404D01*
G01X1152893Y725355D02*
X1152950Y725412D01*
G01D02*
Y726850D01*
G01D02*
X1152400Y727400D01*
G01D02*
Y727600D01*
G01X1159192Y722205D02*
X1161042Y724055D01*
G01D02*
Y730229D01*
G01X1159192Y725355D02*
X1159692Y725855D01*
G01D02*
Y729669D01*
G01D02*
X1157659Y731702D01*
G01X1165492Y725355D02*
Y726008D01*
G01D02*
X1165400Y726100D01*
G01D02*
Y728163D01*
G01D02*
X1166337Y729100D01*
G01D02*
X1168674D01*
G01X1165492Y722205D02*
X1167000Y723713D01*
G01D02*
Y727500D01*
G01X1161042Y730229D02*
X1157000Y734271D01*
G01D02*
Y734500D01*
G01X1157659Y731702D02*
X1157112D01*
G01X1165740Y778485D02*
Y778552D01*
G01D02*
X1165400Y778892D01*
G01D02*
Y780865D01*
G01X1162591Y778485D02*
Y780763D01*
G01X1151392Y789683D02*
X1153417D01*
G01D02*
X1154200Y788900D01*
G01X1153142Y791083D02*
X1154283D01*
G01D02*
X1154700Y791500D01*
G01D02*
Y792678D01*
G01D02*
X1154712Y792690D01*
G01X1165400Y780865D02*
X1165492Y780957D01*
G01X1162591Y780763D02*
X1162693Y780865D01*
G01X1168674Y729100D02*
X1169282Y729708D01*
G54D11*
G01X1Y-17717D02*
G03X7875Y-25591I7874J0D01*
G01X1Y299252D02*
Y-10394D01*
G01Y-17717D02*
G03X7875Y-25591I7874J0D01*
G01X1Y299252D02*
Y-10394D01*
G01Y-17717D02*
Y-10394D01*
G01D02*
Y-17723D01*
G01X0Y11811D02*
Y0D01*
G01X92520Y299252D02*
X1D01*
G01X92520D02*
X1D01*
G01X1008465Y988189D02*
G03X988780Y968504I0J-19685D01*
G01Y775591D01*
G02X984843Y771654I-3937J0D01*
G01X925787D01*
G02X921850Y775591I0J3937D01*
G01Y968504D01*
G03X902165Y988189I-19685J0D01*
G01X800984D01*
G02X797047Y992126I0J3937D01*
G01Y1021653D01*
X795078Y1023622D01*
X754921D01*
X752952Y1021653D01*
X752953Y1018110D01*
Y994291D01*
G02X745472I-3740J0D01*
G01Y1021653D01*
X743504Y1023622D01*
X719094D01*
X717126Y1021653D01*
Y992126D01*
G02X713189Y988189I-3937J0D01*
G01X600984D01*
G02X597047Y992126I0J3937D01*
G01Y1021653D01*
X595078Y1023622D01*
X554921D01*
X552952Y1021653D01*
X552953Y1018110D01*
Y994291D01*
G02X545472I-3741J0D01*
G01Y1021653D01*
X543504Y1023622D01*
X267126D01*
X265157Y1021653D01*
Y992126D01*
G02X261220Y988189I-3937J0D01*
G01X191535D01*
G02X187598Y992126I0J3937D01*
G01Y1021653D01*
X185630Y1023622D01*
X145472D01*
X143504Y1021653D01*
Y994291D01*
G02X136024I-3740J0D01*
G01Y1018110D01*
X136023Y1021653D01*
X134055Y1023622D01*
X109645D01*
X107677Y1021653D01*
Y992126D01*
G02X103740Y988189I-3937J0D01*
G01X19685D01*
G03X0Y968504I0J-19685D01*
G01Y318937D01*
G03X11811Y307126I11811J0D01*
G01X100394D01*
G02X108268Y299252I0J-7874D01*
G01Y236260D01*
G03X116142Y228386I7874J0D01*
G01X239961D01*
G02X243898Y224449I0J-3937D01*
G01Y70866D01*
G03X247835Y66929I3937J0D01*
G01X289173D01*
G02X293110Y62992I0J-3937D01*
G01Y3937D01*
G03X297047Y0I3937J0D01*
G01X1108209D01*
G03X1112146Y3937I0J3937D01*
G01Y210630D01*
G02X1116083Y214567I3937J0D01*
G01X1194823D01*
G02X1198760Y210630I0J-3937D01*
G01Y179134D01*
G03X1202697Y175197I3937J0D01*
G02X1206634Y171260I0J-3937D01*
G01Y3937D01*
G03X1210571Y0I3937J0D01*
G01X1396063D01*
G03X1400000Y3937I0J3937D01*
G01Y968504D01*
G03X1380315Y988189I-19685J0D01*
G01X1008465D01*
G01X0Y318937D02*
G03X11811Y307126I11811J0D01*
G01X0Y968503D02*
Y318937D01*
G01X19685Y988189D02*
G03X0Y968503I0J-19685D01*
G01X43950Y996063D02*
X1D01*
G01X43950D02*
X1D01*
G01Y1008622D02*
Y996063D01*
G01Y1008622D02*
Y996063D01*
G01X15001Y1023622D02*
G03X1Y1008622I0J-15000D01*
G01X15001Y1023622D02*
G03X1Y1008622I0J-15000D01*
G01X7875Y-25591D02*
X45337D01*
G01X7875D02*
X45337D01*
G01X11811Y307126D02*
X100394D01*
G01X10710Y1008622D02*
G03X19292I4291J0D01*
G01D02*
G03X10710I-4291J0D01*
G01X99804Y1023622D02*
X15001D01*
G01X99804D02*
X15001D01*
G01X103740Y988189D02*
X19685D01*
G01X53211Y-25591D02*
G03X45337I-3937J0D01*
G01X53211D02*
G03X45337I-3937J0D01*
G01X53211D02*
G03X45337I-3937J0D01*
G01X53211D02*
G03X45337I-3937J0D01*
G01X43950Y988189D02*
G03Y996063I0J3937D01*
G01Y988189D02*
G03Y996063I0J3937D01*
G01X53211Y-25591D02*
X1392127D01*
G01X53211D02*
X1392127D01*
G01X69147Y996063D02*
G03Y988189I0J-3937D01*
G01Y996063D02*
G03Y988189I0J-3937D01*
G01X99804Y996063D02*
X69147D01*
G01X99804D02*
X69147D01*
G01X94412Y72220D02*
G03X85830Y72219I-4291J-1D01*
G01D02*
G03X94412Y72220I4291J0D01*
G01X100394Y291377D02*
G03X92520Y299252I-7874J1D01*
G01X100394Y291377D02*
G03X92520Y299252I-7874J1D01*
G01X99804Y1023622D02*
Y996063D01*
G01Y1023622D02*
Y996063D01*
G01X100394Y236259D02*
G03X116142Y220511I15748J0D01*
G01D02*
X232088D01*
G01X100394Y236259D02*
G03X116142Y220511I15748J0D01*
G01D02*
X232088D01*
G01X116142Y228385D02*
X239961D01*
G01X108268Y236259D02*
G03X116142Y228385I7874J0D01*
G01X108268Y299252D02*
Y236259D01*
G01X100395Y240899D02*
X100394Y236259D01*
G01X100395Y240899D02*
X100394Y236259D01*
G01X108269Y240899D02*
G03X100395I-3937J0D01*
G01X108269D02*
G03X100395I-3937J0D01*
G01Y266096D02*
G03X108269I3937J-1D01*
G01X100395D02*
G03X108269I3937J-1D01*
G01X100395D02*
X100394Y291377D01*
G01X100395Y266096D02*
X100394Y291377D01*
G01X108268Y299252D02*
G03X100394Y307126I-7874J0D01*
G01X103740Y988189D02*
G03X107677Y992126I0J3937D01*
G01Y1018109D02*
Y992126D01*
G01X136024Y1018109D02*
X136023Y1021653D01*
X134055Y1023622D01*
X109645D01*
X107677Y1021653D01*
Y1018109D01*
G01X136024Y994290D02*
G03X143505I3740J0D01*
G01X136024D02*
Y1018109D01*
G01X143504D02*
Y994290D01*
G01X187598Y1018109D02*
Y1021653D01*
X185630Y1023622D01*
X145472D01*
X143504Y1021653D01*
Y1018109D01*
G01X151575Y220511D02*
X226378D01*
G01X151575D02*
X226378D01*
G01X187598Y992126D02*
Y1018109D01*
G01Y992126D02*
G03X191535Y988189I3937J0D01*
G01X261220D02*
X191535D01*
G01X212681Y996063D02*
X195473D01*
G01D02*
Y1023622D01*
G01X212681Y996063D02*
X195473D01*
G01D02*
Y1023622D01*
G01D02*
X257284D01*
G01X195473D02*
X257284D01*
G01X212681Y988189D02*
G03Y996063I0J3937D01*
G01Y988189D02*
G03Y996063I0J3937D01*
G01X222751Y1008622D02*
G03X231333I4291J0D01*
G01D02*
G03X222751I-4291J0D01*
G01X243898Y70866D02*
G03X247835Y66928I3937J-1D01*
G01X243898Y224448D02*
Y70866D01*
G01X236025Y164487D02*
Y70866D01*
G01D02*
G03X247836Y59055I11811J0D01*
G01X236025Y164487D02*
Y70866D01*
G01D02*
G03X247836Y59055I11811J0D01*
G01X243899Y164487D02*
G03X236025I-3937J0D01*
G01X243899D02*
G03X236025I-3937J0D01*
G01Y189684D02*
G03X243899I3937J0D01*
G01X236025D02*
G03X243899I3937J0D01*
G01X236025D02*
Y216574D01*
G01Y189684D02*
Y216574D01*
G01D02*
G03X232088Y220511I-3937J0D01*
G01X236025Y216574D02*
G03X232088Y220511I-3937J0D01*
G01X243898Y224448D02*
G03X239961Y228385I-3937J0D01*
G01X237877Y996063D02*
G03Y988189I0J-3937D01*
G01Y996063D02*
G03Y988189I0J-3937D01*
G01X257284Y996063D02*
X237877D01*
G01X257284D02*
X237877D01*
G01X247835Y66929D02*
X289174D01*
G01X247836Y59055D02*
X285237D01*
G01X247836D02*
X285237D01*
G01X261220Y988189D02*
G03X265157Y992126I0J3937D01*
G01X257284Y1023622D02*
Y996063D01*
G01Y1023622D02*
Y996063D01*
G01X265157Y1018109D02*
Y992126D01*
G01X545472Y1018109D02*
Y1021653D01*
X543504Y1023622D01*
X267126D01*
X265157Y1021653D01*
Y1018109D01*
G01X293111Y3937D02*
G03X297047Y0I3937J0D01*
G01X293110Y62992D02*
Y3937D01*
G01X285237D02*
G03X297048Y-7874I11811J0D01*
G01X285237Y59055D02*
Y3937D01*
G01D02*
G03X297048Y-7874I11811J0D01*
G01X285237Y59055D02*
Y3937D01*
G01X293111Y62992D02*
G03X289174Y66929I-3937J0D01*
G01X297047Y0D02*
X1108209D01*
G01X297037Y-7874D02*
X301187D01*
G01D02*
G03Y0I0J3937D01*
G01X297037Y-7874D02*
X301187D01*
G01D02*
G03Y0I0J3937D01*
G01X318510Y-7874D02*
X515333D01*
G01X318510Y0D02*
G03Y-7874I0J-3937D01*
G01D02*
X515333D01*
G01X318510Y0D02*
G03Y-7874I0J-3937D01*
G01X515302D02*
G03Y0I0J3937D01*
G01Y-7874D02*
G03Y0I0J3937D01*
G01X540499Y-7874D02*
X727049D01*
G01X540499Y0D02*
G03Y-7874I0J-3937D01*
G01D02*
X727049D01*
G01X540499Y0D02*
G03Y-7874I0J-3937D01*
G01X545472Y994290D02*
G03X552953I3740J1D01*
G01X545472D02*
Y1018109D01*
G01X552953D02*
Y994290D01*
G01X597047Y1018109D02*
Y1021653D01*
X595078Y1023622D01*
X554921D01*
X552952Y1021653D01*
X552953Y1018109D01*
G01X597047Y992126D02*
Y1018109D01*
G01X597048Y992126D02*
G03X600984Y988189I3937J0D01*
G01X713189D02*
X600984D01*
G01X641198Y996063D02*
X604922D01*
G01D02*
Y1023622D01*
G01X641198Y996063D02*
X604922D01*
G01D02*
Y1023622D01*
G01D02*
X709253D01*
G01X604922D02*
X709253D01*
G01X641198Y988189D02*
G03Y996063I0J3937D01*
G01Y988189D02*
G03Y996063I0J3937D01*
G01X649684Y1008622D02*
G03X658266I4291J0D01*
G01D02*
G03X649684I-4291J0D01*
G01X666395Y996063D02*
G03Y988189I0J-3937D01*
G01Y996063D02*
G03Y988189I0J-3937D01*
G01X709253Y996063D02*
X666395D01*
G01X709253D02*
X666395D01*
G01X713189Y988189D02*
G03X717126Y992126I0J3937D01*
G01Y1018109D02*
Y992126D01*
G01X709253Y1023622D02*
Y996063D01*
G01Y1023622D02*
Y996063D01*
G01X745472Y1018109D02*
Y1021653D01*
X743504Y1023622D01*
X719094D01*
X717126Y1021653D01*
Y1018109D01*
G01X727049Y-7874D02*
G03Y0I0J3937D01*
G01Y-7874D02*
G03Y0I0J3937D01*
G01X752246Y-7874D02*
X984201D01*
G01X752246Y0D02*
G03Y-7874I0J-3937D01*
G01D02*
X984201D01*
G01X752246Y0D02*
G03Y-7874I0J-3937D01*
G01X745472Y994290D02*
G03X752953I3741J1D01*
G01X745472D02*
Y1018109D01*
G01X752953D02*
Y994290D01*
G01X797047Y1018109D02*
Y1021653D01*
X795078Y1023622D01*
X754921D01*
X752952Y1021653D01*
X752953Y1018109D01*
G01X797047Y992126D02*
Y1018109D01*
G01X797048Y992126D02*
G03X800984Y988189I3937J0D01*
G01X902165D02*
X800984D01*
G01X859109Y996063D02*
X804922D01*
G01D02*
Y1023622D01*
G01X859109Y996063D02*
X804922D01*
G01D02*
Y1023622D01*
G01D02*
X1325399D01*
G01X804922D02*
X1325399D01*
G01X859109Y988189D02*
G03Y996063I0J3937D01*
G01Y988189D02*
G03Y996063I0J3937D01*
G01X884306D02*
G03Y988189I0J-3937D01*
G01Y996063D02*
G03Y988189I0J-3937D01*
G01X902166Y996063D02*
X884306D01*
G01X902166D02*
X884306D01*
G01X921850Y968503D02*
G03X902165Y988189I-19685J1D01*
G01X929725Y968504D02*
G03X902166Y996063I-27559J0D01*
G01D02*
X902195D01*
G01X929725Y968504D02*
G03X902166Y996063I-27559J0D01*
G01D02*
X902195D01*
G01X921850Y775590D02*
Y968503D01*
G01Y775590D02*
G03X925787Y771653I3937J0D01*
G01X984843D02*
X925787D01*
G01X929725Y779527D02*
Y886881D01*
G01Y779527D02*
X980906D01*
G01X929725D02*
Y886881D01*
G01Y779527D02*
X980906D01*
G01X929725Y886881D02*
G03X921851I-3937J1D01*
G01X929725D02*
G03X921851I-3937J1D01*
G01Y912079D02*
G03X929725I3937J-1D01*
G01X921851D02*
G03X929725I3937J-1D01*
G01Y912078D02*
Y968504D01*
G01Y912078D02*
Y968504D01*
G01X959606Y850829D02*
G03X951024I-4291J0D01*
G01D02*
G03X959606I4291J0D01*
G01X984201Y-7874D02*
G03Y0I0J3937D01*
G01Y-7874D02*
G03Y0I0J3937D01*
G01X984843Y771653D02*
G03X988780Y775590I0J3937D01*
G01X980907Y886881D02*
X980906Y779527D01*
G01X980907Y886881D02*
X980906Y779527D01*
G01X988781Y886881D02*
G03X980907I-3937J1D01*
G01X988781D02*
G03X980907I-3937J1D01*
G01Y912079D02*
G03X988781I3937J-1D01*
G01X980907D02*
G03X988781I3937J-1D01*
G01X980907D02*
X980906Y968504D01*
G01X980907Y912079D02*
X980906Y968504D01*
G01X1008465Y996063D02*
G03X980906Y968504I0J-27559D01*
G01X1008465Y996063D02*
G03X980906Y968504I0J-27559D01*
G01X1011417Y237795D02*
X1005118D01*
G02Y250394I0J6300D01*
G01X1011417D01*
G02Y237795I0J-6299D01*
G01Y405118D02*
X1005118D01*
G02Y417717I0J6300D01*
G01X1011417D01*
G02Y405118I0J-6299D01*
G01X988780Y968503D02*
Y775590D01*
G01X1008465Y988189D02*
G03X988780Y968503I0J-19685D01*
G01X1009398Y-7874D02*
X1108229D01*
G01X1009398Y0D02*
G03Y-7874I-1J-3937D01*
G01D02*
X1108229D01*
G01X1009398Y0D02*
G03Y-7874I-1J-3937D01*
G01X1380315Y988189D02*
X1008465D01*
G01X1070592Y996063D02*
X1008466D01*
G01X1070592D02*
X1008466D01*
G01X1070592Y988189D02*
G03Y996063I0J3937D01*
G01Y988189D02*
G03Y996063I0J3937D01*
G01X1095789D02*
G03Y988189I0J-3937D01*
G01Y996063D02*
G03Y988189I0J-3937D01*
G01X1325399Y996063D02*
X1095789D01*
G01X1325399D02*
X1095789D01*
G01X1112146Y3937D02*
Y210629D01*
G01X1108209Y0D02*
G03X1112146Y3937I0J3937D01*
G01X1108208Y-7874D02*
G03X1120020Y3938I1J11811D01*
G01X1108208Y-7874D02*
G03X1120020Y3938I1J11811D01*
G01Y99950D02*
G03X1112146I-3937J0D01*
G01X1120020D02*
G03X1112146I-3937J0D01*
G01Y125147D02*
G03X1120020I3937J0D01*
G01X1112146D02*
G03X1120020I3937J0D01*
G01X1116083Y214566D02*
X1194824D01*
G01X1116083D02*
G03X1112146Y210629I0J-3937D01*
G01X1120020Y99950D02*
Y3938D01*
G01Y99950D02*
Y3938D01*
G01Y125147D02*
Y206693D01*
G01Y125147D02*
Y206693D01*
G01X1120021D02*
X1190887D01*
G01X1120021D02*
X1190887D01*
G01X1161386Y128841D02*
G03X1152804I-4291J0D01*
G01D02*
G03X1161386I4291J0D01*
G01X1198760Y3937D02*
G03X1210571Y-7874I11811J0D01*
G01X1198760Y3937D02*
G03X1210571Y-7874I11811J0D01*
G01X1198761Y97100D02*
X1198760Y3937D01*
G01X1198761Y97100D02*
X1198760Y3937D01*
G01X1206635Y97100D02*
G03X1198761I-3937J0D01*
G01X1206635D02*
G03X1198761I-3937J0D01*
G01Y122297D02*
G03X1206635I3937J0D01*
G01X1198761D02*
G03X1206635I3937J0D01*
G01X1198761D02*
Y168002D01*
G01Y122297D02*
Y168002D01*
G01X1190887Y179134D02*
G03X1198761Y167998I11811J0D01*
G01X1190887Y179134D02*
G03X1198761Y167998I11811J0D01*
G01X1198760Y179133D02*
G03X1202697Y175196I3937J0D01*
G01X1198760Y210629D02*
Y179133D01*
G01X1190887Y206693D02*
Y179134D01*
G01Y206693D02*
Y179134D01*
G01X1198760Y210629D02*
G03X1194824Y214566I-3937J0D01*
G01X1210571Y0D02*
X1396063D01*
G01X1206634Y3937D02*
G03X1210571Y0I3937J0D01*
G01X1206634Y171259D02*
Y3937D01*
G01X1210552Y-7874D02*
X1210572D01*
G01D02*
G03Y0I0J3937D01*
G01X1210552Y-7874D02*
X1210572D01*
G01D02*
G03Y0I0J3937D01*
G01X1206634Y171259D02*
G03X1202697Y175196I-3937J0D01*
G01X1226320Y-7874D02*
X1380317D01*
G01X1226320Y0D02*
G03Y-7874I0J-3937D01*
G01D02*
X1380317D01*
G01X1226320Y0D02*
G03Y-7874I0J-3937D01*
G01X1230315Y149213D02*
X1224016D01*
G02Y161811I0J6299D01*
G01X1230315D01*
G02Y149213I0J-6299D01*
G01Y405118D02*
X1224016D01*
G02Y417717I0J6300D01*
G01X1230315D01*
G02Y405118I0J-6299D01*
G01X1354801Y996063D02*
X1325399D01*
G01X1354801D02*
X1325399D01*
G01Y1023622D02*
X1385001D01*
G01X1325399D02*
X1385001D01*
G01X1354801Y988189D02*
G03Y996063I0J3937D01*
G01Y988189D02*
G03Y996063I0J3937D01*
G01X1380316Y-7874D02*
G03Y0I0J3937D01*
G01Y-7874D02*
G03Y0I0J3937D01*
G01X1400000Y968503D02*
G03X1380315Y988189I-19685J1D01*
G01X1379998Y996063D02*
G03Y988189I0J-3937D01*
G01Y996063D02*
G03Y988189I0J-3937D01*
G01X1400001Y996063D02*
X1379998D01*
G01X1400001D02*
X1379998D01*
G01X1392127Y-25591D02*
G03X1400001Y-17717I0J7874D01*
G01X1392167Y-15015D02*
G03X1383585I-4291J0D01*
G01D02*
G03X1392167I4291J0D01*
G01X1392127Y-25591D02*
G03X1400001Y-17717I0J7874D01*
G01X1396063Y0D02*
G03X1400000Y3937I0J3937D01*
G01X1396064Y-7874D02*
X1400001D01*
G01X1396064Y0D02*
G03Y-7874I0J-3937D01*
G01D02*
X1400001D01*
G01X1396064Y0D02*
G03Y-7874I0J-3937D01*
G01X1380710Y1008622D02*
G03X1389292I4291J0D01*
G01D02*
G03X1380710I-4291J0D01*
G01X1400001D02*
G03X1385001Y1023622I-15000J0D01*
G01X1400001Y1008622D02*
G03X1385001Y1023622I-15000J0D01*
G01X1400001Y-17717D02*
Y-7874D01*
G01Y-17717D02*
Y-7874D01*
G01X1400000Y3937D02*
Y968503D01*
G01X1400001Y996063D02*
Y1008622D01*
G01Y996063D02*
Y1008622D01*
G54D12*
G01X494554Y331036D02*
X493504Y332086D01*
G01X495242Y338222D02*
X493504Y339960D01*
G01X503895Y328340D02*
X503704Y328532D01*
G01D02*
G02X503640Y328685I153J154D01*
G01D02*
X502872Y329453D01*
G01D02*
G03X502155Y329750I-717J-717D01*
G01D02*
X498459D01*
G01D02*
G02X497855Y330000I0J854D01*
G01D02*
X497055D01*
G01D02*
G02X496463Y330050I1J3537D01*
G01D02*
G02X494554Y331036I592J3487D01*
G01X504850Y329295D02*
G03X504500Y329440I-350J-350D01*
G01D02*
X504095D01*
G01D02*
X503545Y329990D01*
G01D02*
G03X502290Y330510I-1255J-1255D01*
G01D02*
X499455D01*
G01D02*
G02X498708Y330820I1J1057D01*
G01D02*
X497441Y332086D01*
G01X506638Y337783D02*
X506009D01*
G01D02*
G03X505205Y337450I0J-1137D01*
G01D02*
X505055Y337300D01*
G01D02*
G02X503955I-550J550D01*
G01D02*
G03X501666Y338248I-2289J-2289D01*
G01D02*
X497255D01*
G01D02*
G02X496823Y338427I0J611D01*
G01D02*
X496550Y338700D01*
G01D02*
G02X496779Y339298I784J43D01*
G01D02*
X497441Y339960D01*
G01X506638Y336433D02*
X506594D01*
G01D02*
G03X505783Y336769I-811J-811D01*
G01D02*
X505586D01*
G01D02*
G02X503424I-1081J1081D01*
G01D02*
G03X501666Y337498I-1759J-1758D01*
G01D02*
X496499D01*
G01D02*
G02X496118Y337656I0J539D01*
G01D02*
X495242Y338222D01*
G54D13*
G01X341000Y105290D02*
G02X342000Y102876I-2414J-2414D01*
G01D02*
Y102000D01*
G01X347000Y105179D02*
G03X346000Y102765I2414J-2414D01*
G01D02*
Y102000D01*
G01X341000Y108790D02*
Y112790D01*
G01D02*
X343105Y114895D01*
G01D02*
G03X343650Y116211I-1316J1316D01*
G01D02*
Y119638D01*
G01D02*
G02X344590Y121909I3211J1D01*
G01D02*
X345090Y122409D01*
G01X347000Y112679D02*
X345351Y114329D01*
G01D02*
G02X345000Y115175I846J847D01*
G01D02*
Y119638D01*
G01D02*
G02X345545Y120954I1861J0D01*
G01D02*
X346045Y121454D01*
G01D02*
G02X347001Y121850I956J-956D01*
G01X345090Y122409D02*
G02X347000Y123200I1910J-1911D01*
G01Y108679D02*
Y112679D01*
G01X347001Y121850D02*
X362012D01*
G01D02*
G03X363320Y122390I2J1850D01*
G01X347000Y123200D02*
X362012D01*
G01D02*
G03X362365Y123346I0J500D01*
G01D02*
X366509Y127490D01*
G01X367354Y89567D02*
G03X368818Y86032I5000J0D01*
G01D02*
X409118Y45732D01*
G01X366004Y89566D02*
G03X367864Y85076I6350J0D01*
G01D02*
X408163Y44777D01*
G01X375718Y89782D02*
X412768Y52732D01*
G01X372904Y93316D02*
G03X374764Y88826I6350J0D01*
G01D02*
X411813Y51777D01*
G01X367354Y117210D02*
Y89567D01*
G01X366004Y117211D02*
Y89566D01*
G01X374254Y118150D02*
Y93317D01*
G01D02*
G03X375718Y89782I5000J0D01*
G01X372904Y118152D02*
Y93316D01*
G01X376573Y128500D02*
X368818Y120745D01*
G01D02*
G03X367354Y117210I3536J-3535D01*
G01X374883Y128720D02*
X367864Y121701D01*
G01D02*
G03X366004Y117211I4490J-4490D01*
G01X379232Y125200D02*
X375718Y121685D01*
G01D02*
G03X374254Y118150I3536J-3535D01*
G01X374764Y122642D02*
G03X372904Y118152I4490J-4490D01*
G01X363320Y122390D02*
X366644Y125715D01*
G01X376181Y134645D02*
Y134059D01*
G01D02*
G03X376518Y133246I1149J0D01*
G01D02*
X377172Y132592D01*
G01D02*
G02X377656Y131424I-1167J-1168D01*
G01D02*
Y130690D01*
G01D02*
G02X376875Y128803I-2668J-1D01*
G01D02*
X376573Y128500D01*
G01X376181Y131496D02*
G02X375137Y128974I-3566J-1D01*
G01D02*
X374883Y128721D01*
G01D02*
Y128720D01*
G01X379331Y134645D02*
X380107Y133869D01*
G01X379456Y129000D02*
G02X378277Y126155I-4024J1D01*
G01D02*
X374764Y122642D01*
G01X366509Y127490D02*
G03X367009Y128697I-1207J1207D01*
G01D02*
Y130830D01*
G01D02*
G03X366733Y131496I-942J0D01*
G01X366644Y125715D02*
X367464Y126535D01*
G01D02*
G03X368359Y128696I-2162J2161D01*
G01D02*
Y128758D01*
G01D02*
G02X369218Y130832I2933J0D01*
G01D02*
X369882Y131496D01*
G01X379331Y140945D02*
X378636D01*
G01D02*
G03X378283Y140799I0J-500D01*
G01D02*
X377984Y140500D01*
G01D02*
G03X377750Y139935I565J-565D01*
G01D02*
Y139400D01*
G01X379331Y144094D02*
X377757Y142520D01*
G01X376181Y140945D02*
G03X375657Y140728I0J-741D01*
G01D02*
X374699Y139770D01*
G01D02*
G03X374600Y139530I240J-239D01*
G01D02*
Y139390D01*
G01X376181Y144094D02*
X374607Y142520D01*
G01X382618Y93032D02*
X415918Y59732D01*
G01X381664Y92076D02*
X414963Y58777D01*
G01X388564Y96076D02*
X403860Y80780D01*
G01X381154Y117543D02*
Y96567D01*
G01D02*
G03X382618Y93032I5000J0D01*
G01X379804Y117544D02*
Y96566D01*
G01D02*
G03X381664Y92076I6350J0D01*
G01X388054Y119500D02*
Y100567D01*
G01D02*
G03X389518Y97032I5000J0D01*
G01D02*
X420112Y66439D01*
G01X386704Y119501D02*
Y100566D01*
G01D02*
G03X388564Y96076I6350J0D01*
G01X394954Y120526D02*
Y103567D01*
G01D02*
G03X396418Y100032I5000J0D01*
G01X393604Y120525D02*
Y103566D01*
G01D02*
G03X395464Y99076I6350J0D01*
G01D02*
X422056Y72484D01*
G01X386299Y124759D02*
X382618Y121078D01*
G01D02*
G03X381154Y117543I3536J-3535D01*
G01X385344Y125714D02*
X381664Y122034D01*
G01D02*
G03X379804Y117544I4490J-4490D01*
G01X390255Y123579D02*
G02X389449Y121634I-2752J1D01*
G01D02*
X388657Y120842D01*
G01D02*
X388577Y120761D01*
G01D02*
G03X388054Y119500I1261J-1262D01*
G01X388494Y122589D02*
X387696Y121791D01*
G01D02*
X387619Y121713D01*
G01D02*
G03X386704Y119501I2219J-2213D01*
G01X396529Y124329D02*
G02X395379Y121550I-3928J-2D01*
G01D02*
G03X394955Y120525I1025J-1024D01*
G01D02*
X394954Y120526D01*
G01X394424Y122505D02*
G03X393604Y120525I1980J-1980D01*
G01X380107Y133869D02*
G02X380806Y132182I-1686J-1687D01*
G01D02*
Y128999D01*
G01D02*
G02X379232Y125200I-5374J1D01*
G01X379331Y131496D02*
G02X379456Y131194I-302J-302D01*
G01D02*
Y129000D01*
G01X385630Y134645D02*
X386097Y134177D01*
G01D02*
G02X387105Y131745I-2432J-2433D01*
G01D02*
Y126705D01*
G01D02*
G02X386299Y124759I-2752J0D01*
G01X385630Y131496D02*
G02X385755Y131194I-302J-302D01*
G01D02*
Y126705D01*
G01D02*
G02X385344Y125714I-1402J1D01*
G01X388780Y134645D02*
Y134148D01*
G01D02*
G03X389055Y133485I937J0D01*
G01D02*
X389642Y132898D01*
G01D02*
G02X390255Y131419I-1478J-1479D01*
G01D02*
Y129646D01*
G01D02*
X390254Y129645D01*
G01D02*
Y128257D01*
G01D02*
X390255Y128256D01*
G01D02*
Y123579D01*
G01X388780Y131496D02*
G02X388904Y131197I-299J-299D01*
G01D02*
Y127697D01*
G01D02*
X388905Y127696D01*
G01D02*
Y123580D01*
G01D02*
G02X388494Y122589I-1402J1D01*
G01X395079Y134645D02*
X395613Y134110D01*
G01D02*
G02X396529Y131900I-2210J-2211D01*
G01X395079Y131496D02*
G02X395179Y131255I-241J-241D01*
G01D02*
Y124328D01*
G01D02*
G02X394424Y122505I-2578J0D01*
G01X385630Y140945D02*
X385593D01*
G01D02*
X384019Y139371D01*
G01X385630Y144094D02*
X384056Y142520D01*
G01X395079Y140945D02*
Y140909D01*
G01D02*
X393510Y139340D01*
G01X395079Y144094D02*
X393505Y142520D01*
G01X388780Y140945D02*
X388742D01*
G01D02*
X387173Y139376D01*
G01X388780Y144094D02*
X387206Y142520D01*
G01X409118Y45732D02*
G03X410886Y45000I1768J1768D01*
G01D02*
X428905D01*
G01X408163Y44777D02*
G03X410886Y43650I2722J2723D01*
G01D02*
X428904D01*
G01X411813Y51777D02*
G03X414536Y50650I2722J2723D01*
G01X403860Y80780D02*
X419157Y65484D01*
G01X396418Y100032D02*
X423011Y73439D01*
G01X402104Y106489D02*
G03X403568Y102954I5000J0D01*
G01D02*
X425651Y80871D01*
G01X400754Y106488D02*
G03X402614Y101998I6350J0D01*
G01D02*
X424696Y79916D01*
G01X409004Y109348D02*
G03X410468Y105813I5000J0D01*
G01D02*
X428511Y87770D01*
G01X407654Y109347D02*
G03X409514Y104857I6350J0D01*
G01D02*
X427555Y86816D01*
G01X402104Y122660D02*
Y106489D01*
G01X400754Y122659D02*
Y106488D01*
G01X406393Y123052D02*
G03X406804Y122061I1402J1D01*
G01D02*
X408198Y120667D01*
G01D02*
G02X409004Y118722I-1946J-1946D01*
G01D02*
Y109348D01*
G01X405043Y123052D02*
G03X405849Y121106I2752J0D01*
G01D02*
X407243Y119712D01*
G01D02*
G02X407654Y118721I-991J-992D01*
G01D02*
Y109347D01*
G01X408608Y125134D02*
X414143Y119599D01*
G01X396529Y131900D02*
Y124329D01*
G01X398229Y134645D02*
X398395D01*
G01D02*
X399187Y133853D01*
G01D02*
G02X399903Y132125I-1727J-1728D01*
G01D02*
Y126580D01*
G01D02*
G03X400314Y125589I1402J1D01*
G01D02*
X401298Y124605D01*
G01D02*
G02X402104Y122660I-1946J-1946D01*
G01X398229Y131496D02*
X398553Y131172D01*
G01D02*
Y126580D01*
G01D02*
G03X399359Y124634I2752J0D01*
G01D02*
X400343Y123650D01*
G01D02*
G02X400754Y122659I-991J-992D01*
G01X404528Y134645D02*
Y134512D01*
G01D02*
X405351Y133689D01*
G01D02*
G02X406003Y132115I-1574J-1574D01*
G01D02*
Y130676D01*
G01D02*
G03X406198Y130205I666J0D01*
G01D02*
G02X406393Y129734I-471J-471D01*
G01D02*
Y123052D01*
G01X404528Y131496D02*
X404653Y131371D01*
G01D02*
Y130152D01*
G01D02*
G03X404848Y129681I666J0D01*
G01D02*
G02X405043Y129210I-471J-471D01*
G01D02*
Y123052D01*
G01X407677Y134645D02*
Y134059D01*
G01D02*
G03X408014Y133246I1149J0D01*
G01D02*
X408668Y132592D01*
G01D02*
G02X409152Y131424I-1167J-1168D01*
G01D02*
Y127080D01*
G01D02*
G03X409563Y126089I1402J1D01*
G01D02*
X415098Y120554D01*
G01X407677Y131496D02*
G02X407802Y131194I-302J-302D01*
G01D02*
Y127080D01*
G01D02*
G03X408608Y125134I2752J0D01*
G01X398229Y140945D02*
X397581D01*
G01D02*
G03X397228Y140799I0J-500D01*
G01D02*
X396829Y140400D01*
G01D02*
G03X396683Y140047I354J-353D01*
G01D02*
Y139362D01*
G01X398229Y144094D02*
X396655Y142520D01*
G01X407677Y140945D02*
X406103Y139371D01*
G01X407677Y144094D02*
X406103Y142520D01*
G01X404528Y140945D02*
X402953Y139370D01*
G01X404528Y144094D02*
X402954Y142520D01*
G01X412768Y52732D02*
G03X414536Y52000I1768J1768D01*
G01D02*
X429905D01*
G01X414536Y50650D02*
X429904D01*
G01X415918Y59732D02*
G03X417686Y59000I1768J1768D01*
G01D02*
X430905D01*
G01X414963Y58777D02*
G03X417686Y57650I2722J2723D01*
G01D02*
X430904D01*
G01X420112Y66439D02*
G03X421172Y66000I1060J1061D01*
G01D02*
X431905D01*
G01X419157Y65484D02*
G03X421171Y64650I2015J2016D01*
G01D02*
X431904D01*
G01X423011Y73439D02*
G03X424071Y73000I1060J1061D01*
G01D02*
X433405D01*
G01X422056Y72484D02*
G03X424070Y71650I2015J2016D01*
G01D02*
X433404D01*
G01X425651Y80871D02*
G03X427419Y80138I1768J1767D01*
G01D02*
X434267D01*
G01X424696Y79916D02*
G03X427418Y78788I2723J2722D01*
G01D02*
X434266D01*
G01X427555Y86816D02*
G03X430278Y85688I2723J2722D01*
G01X417368Y108672D02*
X431691Y94349D01*
G01X416414Y107716D02*
X430736Y93394D01*
G01X415098Y120554D02*
G02X415904Y118609I-1946J-1946D01*
G01D02*
Y112207D01*
G01D02*
G03X417368Y108672I5000J0D01*
G01X414143Y119599D02*
G02X414554Y118608I-991J-992D01*
G01D02*
Y112206D01*
G01D02*
G03X416414Y107716I6350J0D01*
G01X431628Y43872D02*
X460418Y15082D01*
G01X430672Y42918D02*
X459462Y14128D01*
G01X432628Y50872D02*
X461418Y22082D01*
G01X431672Y49918D02*
X460462Y21128D01*
G01X428905Y45000D02*
G02X431628Y43872I0J-3850D01*
G01X428904Y43650D02*
G02X430672Y42918I0J-2500D01*
G01X429905Y52000D02*
G02X432628Y50872I0J-3850D01*
G01X429904Y50650D02*
G02X431672Y49918I0J-2500D01*
G01X433628Y57872D02*
X462518Y28982D01*
G01X432672Y56918D02*
X461562Y28028D01*
G01X434628Y64872D02*
X463418Y36082D01*
G01X433672Y63918D02*
X462462Y35128D01*
G01X430905Y59000D02*
G02X433628Y57872I0J-3850D01*
G01X430904Y57650D02*
G02X432672Y56918I0J-2500D01*
G01X431905Y66000D02*
G02X434628Y64872I0J-3850D01*
G01X431904Y64650D02*
G02X433672Y63918I0J-2500D01*
G01X433405Y73000D02*
G02X436128Y71872I0J-3850D01*
G01D02*
X465018Y42982D01*
G01X433404Y71650D02*
G02X435172Y70918I0J-2500D01*
G01D02*
X464062Y42028D01*
G01X436990Y79010D02*
X465418Y50582D01*
G01X436034Y78056D02*
X464462Y49628D01*
G01X434267Y80138D02*
G02X436990Y79010I0J-3850D01*
G01X434266Y78788D02*
G02X436034Y78056I0J-2500D01*
G01X428511Y87770D02*
G03X430279Y87038I1768J1768D01*
G01D02*
X435801D01*
G01D02*
G02X438482Y85927I-1J-3793D01*
G01D02*
X466328Y58082D01*
G01X430278Y85688D02*
X435800D01*
G01D02*
G02X437527Y84972I-1J-2443D01*
G01D02*
X465372Y57128D01*
G01X431691Y94349D02*
G03X432682Y93938I992J991D01*
G01D02*
X453867D01*
G01X430736Y93394D02*
G03X432681Y92588I1946J1946D01*
G01D02*
X453868D01*
G01X460418Y15082D02*
G03X462186Y14350I1768J1768D01*
G01X459462Y14128D02*
G03X462185Y13000I2723J2722D01*
G01X460462Y21128D02*
G03X463185Y20000I2723J2722D01*
G01X453867Y93938D02*
G03X457402Y95402I0J5000D01*
G01D02*
X464199Y102199D01*
G01X453868Y92588D02*
G03X458358Y94448I0J6350D01*
G01D02*
X465153Y101243D01*
G01X462186Y14350D02*
X537212D01*
G01X462185Y13000D02*
X537211D01*
G01X461418Y22082D02*
G03X463186Y21350I1768J1768D01*
G01D02*
X534304D01*
G01X463185Y20000D02*
X534303D01*
G01X462518Y28982D02*
G03X464286Y28250I1768J1768D01*
G01D02*
X530604D01*
G01X461562Y28028D02*
G03X464285Y26900I2723J2722D01*
G01D02*
X530603D01*
G01X463418Y36082D02*
G03X465186Y35350I1768J1768D01*
G01D02*
X525804D01*
G01X462462Y35128D02*
G03X465185Y34000I2723J2722D01*
G01D02*
X525803D01*
G01X465018Y42982D02*
G03X466786Y42250I1768J1768D01*
G01D02*
X520114D01*
G01X464062Y42028D02*
G03X466785Y40900I2723J2722D01*
G01D02*
X520117D01*
G01X465418Y50582D02*
G03X467186Y49850I1768J1768D01*
G01D02*
X516404D01*
G01X464462Y49628D02*
G03X467185Y48500I2723J2722D01*
G01D02*
X516403D01*
G01X465372Y57128D02*
G03X468095Y56000I2723J2722D01*
G01D02*
X513096D01*
G01X466328Y58082D02*
G03X468096Y57350I1768J1768D01*
G01D02*
X513095D01*
G01X464199Y102199D02*
G03X464930Y103966I-1768J1766D01*
G01D02*
X464931Y103965D01*
G01D02*
Y105871D01*
G01D02*
G02X468560Y109500I3629J0D01*
G01X465153Y101243D02*
G03X466281Y103966I-2722J2723D01*
G01D02*
Y105871D01*
G01D02*
G02X468560Y108150I2279J0D01*
G01Y109500D02*
X537205D01*
G01X468560Y108150D02*
X537206D01*
G01X525804Y35350D02*
G03X527572Y36082I0J2500D01*
G01X525803Y34000D02*
G03X528527Y35127I2J3850D01*
G01X520114Y42250D02*
G03X521882Y42982I0J2500D01*
G01D02*
X529800Y50900D01*
G01X520117Y40900D02*
G03X522840Y42028I0J3850D01*
G01D02*
X530755Y49945D01*
G01X516404Y49850D02*
G03X518172Y50582I0J2500D01*
G01D02*
X523945Y56355D01*
G01D02*
G03X525900Y61074I-4718J4719D01*
G01X516403Y48500D02*
G03X519127Y49627I2J3850D01*
G01D02*
X524900Y55400D01*
G01D02*
G03X527250Y61073I-5673J5673D01*
G01X513096Y56000D02*
G03X517200Y57700I0J5804D01*
G01X525900Y61074D02*
Y74770D01*
G01X513095Y57350D02*
G03X516245Y58655I0J4454D01*
G01D02*
G03X519000Y65304I-6650J6651D01*
G01D02*
Y77870D01*
G01X517200Y57700D02*
G03X520350Y65305I-7605J7605D01*
G01D02*
Y77869D01*
G01X525900Y74770D02*
G02X527760Y79260I6350J0D01*
G01X519000Y77870D02*
G02X520860Y82360I6350J0D01*
G01D02*
X625681Y187181D01*
G01X520350Y77869D02*
G02X521814Y81404I5000J0D01*
G01D02*
X626635Y186225D01*
G01X537212Y14350D02*
G03X540845Y15855I0J5137D01*
G01D02*
X560545Y35555D01*
G01X537211Y13000D02*
G03X541800Y14900I2J6487D01*
G01D02*
X561500Y34600D01*
G01X534304Y21350D02*
G03X536072Y22082I0J2500D01*
G01D02*
X554045Y40055D01*
G01X534303Y20000D02*
G03X537027Y21127I2J3850D01*
G01D02*
X555000Y39100D01*
G01X530604Y28250D02*
G03X532372Y28982I0J2500D01*
G01D02*
X546895Y43505D01*
G01X530603Y26900D02*
G03X533327Y28027I2J3850D01*
G01D02*
X547850Y42550D01*
G01X527572Y36082D02*
X539145Y47655D01*
G01X528527Y35127D02*
X540100Y46700D01*
G01X539145Y47655D02*
G03X541000Y52132I-4477J4478D01*
G01D02*
Y70111D01*
G01X540100Y46700D02*
G03X542350Y52132I-5432J5432D01*
G01D02*
Y70110D01*
G01X529800Y50900D02*
G03X533500Y59833I-8933J8933D01*
G01X530755Y49945D02*
G03X534850Y59834I-9888J9887D01*
G01X541000Y70111D02*
G02X542859Y74600I6350J0D01*
G01X542350Y70110D02*
G02X543814Y73645I5000J0D01*
G01X533500Y59833D02*
Y72370D01*
G01D02*
G02X535360Y76860I6350J0D01*
G01X534850Y59834D02*
Y72369D01*
G01D02*
G02X536314Y75904I5000J0D01*
G01X527250Y61073D02*
Y74769D01*
G01X542859Y74600D02*
X751129Y282870D01*
G01X535360Y76860D02*
X657176Y198676D01*
G01X536314Y75904D02*
X658130Y197720D01*
G01X527760Y79260D02*
X641426Y192926D01*
G01X527250Y74769D02*
G02X528714Y78304I5000J0D01*
G01D02*
X642380Y191970D01*
G01X537205Y109500D02*
G03X538973Y110232I0J2500D01*
G01D02*
X609931Y181190D01*
G01X537206Y108150D02*
G03X539929Y109278I0J3850D01*
G01D02*
X610885Y180234D01*
G01X554045Y40055D02*
G03X555900Y44531I-4477J4478D01*
G01X555000Y39100D02*
G03X557250Y44532I-5432J5432D01*
G01X555900Y44531D02*
Y64770D01*
G01X557250Y44532D02*
Y64769D01*
G01X546895Y43505D02*
G03X548999Y48586I-5081J5080D01*
G01D02*
X549000Y48585D01*
G01D02*
Y68352D01*
G01X547850Y42550D02*
G03X550350Y48586I-6036J6036D01*
G01D02*
Y68351D01*
G01X555900Y64770D02*
G02X557759Y69259I6350J0D01*
G01D02*
X729722Y241222D01*
G01X557250Y64769D02*
G02X558714Y68304I5000J0D01*
G01D02*
X730678Y240268D01*
G01X549000Y68352D02*
G02X550465Y72407I6350J-2D01*
G01D02*
Y72447D01*
G01D02*
X727470Y249452D01*
G01X550350Y68351D02*
G02X551504Y71544I4999J-2D01*
G01D02*
G02X551815Y71886I3850J-3189D01*
G01D02*
X728218Y248289D01*
G01X543814Y73645D02*
X752084Y281915D01*
G01X560545Y35555D02*
G03X562999Y41481I-5926J5925D01*
G01X561500Y34600D02*
G03X564350Y41481I-6881J6881D01*
G01X562999D02*
X563000Y41480D01*
G01D02*
Y61370D01*
G01X564350Y41481D02*
Y61369D01*
G01X563000Y61370D02*
G02X564859Y65859I6350J0D01*
G01D02*
X729140Y230140D01*
G01X564350Y61369D02*
G02X565814Y64904I5000J0D01*
G01D02*
X730096Y229186D01*
G01X609931Y181190D02*
G03X611395Y184725I-3536J3535D01*
G01D02*
Y291572D01*
G01X610885Y180234D02*
G03X612745Y184724I-4490J4490D01*
G01D02*
Y291571D01*
G01X611395Y291572D02*
G02X612083Y293233I2350J0D01*
G01D02*
X613925Y295075D01*
G01D02*
G03X615310Y298419I-3344J3344D01*
G01D02*
Y299996D01*
G01D02*
G03X613962Y303250I-4602J0D01*
G01X612745Y291571D02*
G02X613038Y292278I1000J0D01*
G01D02*
X614880Y294120D01*
G01D02*
G03X616660Y298419I-4299J4298D01*
G01D02*
Y300430D01*
G01D02*
G02X617828Y303250I3988J0D01*
G01X625681Y187181D02*
G03X627145Y190716I-3536J3535D01*
G01X626635Y186225D02*
G03X628495Y190715I-4490J4490D01*
G01X641426Y192926D02*
G03X642890Y196461I-3536J3535D01*
G01X627145Y190716D02*
Y291100D01*
G01X628495Y190715D02*
Y291100D01*
G01X627145D02*
G02X628166Y293566I3487J1D01*
G01D02*
X630355Y295755D01*
G01D02*
G03X631059Y297456I-1701J1700D01*
G01D02*
X631060Y297455D01*
G01D02*
Y299996D01*
G01D02*
G03X629712Y303250I-4602J0D01*
G01X628495Y291100D02*
G02X629121Y292611I2137J0D01*
G01D02*
X631310Y294800D01*
G01D02*
G03X632410Y297456I-2656J2656D01*
G01D02*
Y300430D01*
G01D02*
G02X633578Y303250I3988J0D01*
G01X657176Y198676D02*
G03X658640Y202211I-3536J3535D01*
G01X658130Y197720D02*
G03X659990Y202210I-4490J4490D01*
G01X642890Y196461D02*
Y291100D01*
G01X642380Y191970D02*
G03X644240Y196460I-4490J4490D01*
G01D02*
Y291100D01*
G01X642890D02*
G02X643911Y293566I3487J1D01*
G01D02*
X646100Y295755D01*
G01D02*
G03X646804Y297456I-1701J1700D01*
G01D02*
X646805Y297455D01*
G01D02*
Y299996D01*
G01D02*
G03X645457Y303250I-4602J0D01*
G01X644240Y291100D02*
G02X644866Y292611I2137J0D01*
G01D02*
X647055Y294800D01*
G01D02*
G03X648155Y297456I-2656J2656D01*
G01D02*
Y300430D01*
G01D02*
G02X649323Y303250I3988J0D01*
G01X675213Y103524D02*
G03X674358Y103170I0J-1209D01*
G01X675328Y99024D02*
G02X674469Y99380I0J1215D01*
G01X658640Y202211D02*
Y291100D01*
G01X659990Y202210D02*
Y291100D01*
G01X658640D02*
G02X659661Y293566I3487J1D01*
G01D02*
X661850Y295755D01*
G01D02*
G03X662554Y297456I-1701J1700D01*
G01D02*
X662555Y297455D01*
G01D02*
Y299996D01*
G01D02*
G03X661207Y303250I-4602J0D01*
G01X659990Y291100D02*
G02X660616Y292611I2137J0D01*
G01D02*
X662805Y294800D01*
G01D02*
G03X663905Y297456I-2656J2656D01*
G01D02*
Y300430D01*
G01D02*
G02X665073Y303250I3988J0D01*
G01X687966Y92294D02*
Y88544D01*
G01X678076Y103524D02*
X675213D01*
G01X678076Y99024D02*
X675328D01*
G01X681576Y103524D02*
X685474D01*
G01D02*
X685748Y103250D01*
G01X681576Y103524D02*
X685336Y107284D01*
G01X693087Y101699D02*
X688148D01*
G01D02*
G02X686698Y102299I-1J2050D01*
G01D02*
X685748Y103249D01*
G01D02*
Y103250D01*
G01X681576Y99024D02*
X685326Y95274D01*
G01D02*
Y94934D01*
G01D02*
X687966Y92294D01*
G01X681576Y99024D02*
X681826Y99274D01*
G01D02*
X685272D01*
G01D02*
X685748Y99750D01*
G01D02*
G02X687194Y100349I1446J-1446D01*
G01D02*
X693087D01*
G01X690512Y122514D02*
X690498Y122500D01*
G01D02*
Y119384D01*
G01D02*
G03X690924Y118356I1454J0D01*
G01D02*
G03X691865Y118120I942J1761D01*
G01X682382Y122692D02*
X682574Y122500D01*
G01X686998D02*
Y121158D01*
G01D02*
G03X687640Y119608I2192J0D01*
G01D02*
X689498Y117750D01*
G01D02*
G03X691864Y116770I2366J2367D01*
G01X685336Y107284D02*
Y107744D01*
G01D02*
X685186Y107894D01*
G01D02*
Y114964D01*
G01X690512Y126202D02*
X690452Y126262D01*
G01D02*
X686432D01*
G01X690512Y126202D02*
Y122514D01*
G01X678222Y122842D02*
X678372Y122692D01*
G01D02*
X682382D01*
G01X682574Y122500D02*
X686998D01*
G01X686432Y129762D02*
X686396Y129798D01*
G01D02*
G02X685898Y131000I1202J1202D01*
G01D02*
Y133380D01*
G01X682382Y126192D02*
Y129944D01*
G01D02*
X682418Y129980D01*
G01X696598Y111104D02*
Y105138D01*
G01D02*
G02X696133Y104015I-1588J0D01*
G01D02*
X694333Y102215D01*
G01D02*
G02X693087Y101699I-1246J1246D01*
G01Y100349D02*
G03X695288Y101260I1J3112D01*
G01D02*
X697088Y103060D01*
G01D02*
G03X697948Y105138I-2078J2077D01*
G01D02*
Y111103D01*
G01X691865Y118120D02*
X694560D01*
G01D02*
G03X696093Y118755I0J2168D01*
G01D02*
X698193Y120855D01*
G01D02*
G02X701152Y122080I2958J-2959D01*
G01D02*
X705228D01*
G01D02*
X705322Y122174D01*
G01D02*
G02X705549Y122268I227J-227D01*
G01D02*
X708216D01*
G01X691864Y116770D02*
X694561D01*
G01D02*
G03X697048Y117800I0J3518D01*
G01D02*
X699148Y119900D01*
G01D02*
G02X701152Y120730I2004J-2004D01*
G01D02*
X704811D01*
G01D02*
G02X705164Y120584I0J-500D01*
G01D02*
X705302Y120446D01*
G01D02*
G03X705655Y120300I353J354D01*
G01D02*
X708216D01*
G01Y116363D02*
X705818D01*
G01D02*
G03X705465Y116217I0J-500D01*
G01D02*
X705234Y115986D01*
G01D02*
G02X704881Y115840I-353J354D01*
G01D02*
X701249D01*
G01D02*
G03X699028Y114920I1J-3142D01*
G01D02*
X697578Y113470D01*
G01D02*
G03X696598Y111104I2367J-2366D01*
G01X697948Y111103D02*
G02X698533Y112515I1997J0D01*
G01D02*
X699983Y113965D01*
G01D02*
G02X701250Y114490I1267J-1267D01*
G01D02*
X704852D01*
G01D02*
G03X705084Y114394I232J232D01*
G01D02*
X708216D01*
G01X729140Y230140D02*
G02X733630Y232000I4490J-4490D01*
G01D02*
X743447D01*
G01X730096Y229186D02*
G02X733631Y230650I3535J-3536D01*
G01D02*
X743448D01*
G01X729722Y241222D02*
G02X732445Y242350I2723J-2722D01*
G01D02*
X738404D01*
G01D02*
G03X740172Y243082I0J2500D01*
G01D02*
X783589Y286499D01*
G01X730678Y240268D02*
G02X732446Y241000I1768J-1768D01*
G01D02*
X738405D01*
G01D02*
G03X741128Y242128I0J3850D01*
G01X727470Y249452D02*
G02X730000Y250500I2530J-2530D01*
G01D02*
G03X731860Y251271I-1J2631D01*
G01D02*
X732795Y252205D01*
G01D02*
X767671Y287081D01*
G01X728218Y248289D02*
Y248290D01*
G01D02*
X728425Y248497D01*
G01D02*
G02X730000Y249149I1575J-1575D01*
G01D02*
G03X732815Y250316I-1J3981D01*
G01D02*
X733750Y251250D01*
G01D02*
X768626Y286126D01*
G01X743447Y232000D02*
G03X746982Y233464I0J5000D01*
G01D02*
X799567Y286049D01*
G01X743448Y230650D02*
G03X747938Y232510I0J6350D01*
G01D02*
X800522Y285094D01*
G01X741128Y242128D02*
X784544Y285544D01*
G01X751129Y282870D02*
G03X753130Y287701I-4831J4831D01*
G01X752084Y281915D02*
G03X754480Y287702I-5786J5785D01*
G01X753130Y287701D02*
Y291100D01*
G01D02*
G02X754150Y293566I3487J2D01*
G01D02*
X755246Y294661D01*
G01D02*
X756340Y295755D01*
G01D02*
G03X757044Y297456I-1701J1700D01*
G01X757045Y299996D02*
G03X755697Y303250I-4602J0D01*
G01X754480Y287702D02*
Y291099D01*
G01D02*
X754481Y291100D01*
G01D02*
G02X755106Y292611I2136J1D01*
G01D02*
X757295Y294800D01*
G01X768626Y286126D02*
G03X770230Y290001I-3874J3873D01*
G01X767671Y287081D02*
G03X768880Y290000I-2919J2919D01*
G01D02*
Y291100D01*
G01D02*
G02X769901Y293566I3487J1D01*
G01D02*
X772090Y295755D01*
G01D02*
G03X772794Y297456I-1701J1700D01*
G01D02*
X772795Y297455D01*
G01D02*
Y299996D01*
G01D02*
G03X771447Y303250I-4602J0D01*
G01X770230Y290001D02*
Y291100D01*
G01D02*
G02X770856Y292611I2137J0D01*
G01D02*
X773045Y294800D01*
G01D02*
G03X774145Y297456I-2656J2656D01*
G01X757044D02*
X757045Y297455D01*
G01D02*
Y299996D01*
G01X757295Y294800D02*
G03X758395Y297456I-2656J2656D01*
G01D02*
Y300430D01*
G01D02*
G02X759563Y303250I3988J0D01*
G01X783589Y286499D02*
G03X784625Y289000I-2501J2501D01*
G01X784544Y285544D02*
G03X785975Y288999I-3456J3455D01*
G01X784625Y289000D02*
Y291500D01*
G01D02*
G02X785363Y293283I2521J1D01*
G01D02*
X787835Y295755D01*
G01D02*
G03X788539Y297456I-1701J1700D01*
G01D02*
X788540Y297455D01*
G01D02*
Y299996D01*
G01D02*
G03X787192Y303250I-4602J0D01*
G01X785975Y288999D02*
Y291500D01*
G01D02*
G02X786318Y292328I1171J0D01*
G01D02*
X788790Y294800D01*
G01D02*
G03X789890Y297456I-2656J2656D01*
G01X774145D02*
Y300430D01*
G01D02*
G02X775313Y303250I3988J0D01*
G01X799567Y286049D02*
G03X800375Y288000I-1951J1951D01*
G01X800522Y285094D02*
G03X801725Y288001I-2906J2905D01*
G01X800375Y288000D02*
Y290500D01*
G01D02*
G02X801821Y293991I4937J0D01*
G01D02*
X803585Y295755D01*
G01D02*
G03X804289Y297456I-1701J1700D01*
G01D02*
X804290Y297455D01*
G01D02*
Y299996D01*
G01D02*
G03X802942Y303250I-4602J0D01*
G01X801725Y288001D02*
Y290500D01*
G01D02*
G02X802776Y293036I3587J-1D01*
G01D02*
X804540Y294800D01*
G01D02*
G03X805640Y297456I-2656J2656D01*
G01D02*
Y300430D01*
G01D02*
G02X806808Y303250I3988J0D01*
G01X789890Y297456D02*
Y300430D01*
G01D02*
G02X791058Y303250I3988J0D01*
G01X1066929Y43267D02*
X1069137D01*
G01D02*
G03X1069700Y43500I0J796D01*
G01D02*
G03X1070191Y44685I-1185J1185D01*
G01D02*
Y52100D01*
G01D02*
G02X1071605Y55515I4829J1D01*
G01D02*
X1085626Y69536D01*
G01X1074803Y43267D02*
X1073187D01*
G01D02*
G02X1071900Y43800I0J1820D01*
G01D02*
G02X1071541Y44667I867J867D01*
G01D02*
Y52100D01*
G01D02*
G02X1072560Y54560I3479J0D01*
G01D02*
X1086581Y68581D01*
G01X1085626Y69536D02*
G02X1088800Y70850I3173J-3175D01*
G01D02*
X1092310D01*
G01D02*
G03X1093045Y71155I-1J1040D01*
G01D02*
G03X1094249Y74063I-2908J2907D01*
G01X1086581Y68581D02*
G02X1088800Y69500I2219J-2219D01*
G01D02*
X1092310D01*
G01D02*
G03X1094000Y70200I0J2390D01*
G01D02*
G03X1095600Y74063I-3863J3863D01*
G01X1094249D02*
X1094250Y74062D01*
G01D02*
Y79700D01*
G01X1092400Y87700D02*
Y86397D01*
G01D02*
G03X1092900Y85190I1707J0D01*
G01D02*
X1093795Y84295D01*
G01D02*
Y84294D01*
G01D02*
G02X1094250Y83197I-1097J-1098D01*
G01D02*
Y79700D01*
G01X1095600Y74063D02*
Y75534D01*
G01D02*
G02X1096000Y76500I1366J0D01*
G01D02*
G03X1096500Y77707I-1207J1207D01*
G01D02*
Y83700D01*
G01D02*
G03X1095900Y84300I-600J0D01*
G01D02*
G02X1095558Y84441I-1J483D01*
G01D02*
X1094750Y85250D01*
G01D02*
G02X1094250Y86457I1207J1207D01*
G01D02*
Y90300D01*
G01X1090061Y104842D02*
Y106491D01*
G01X1093861Y104842D02*
Y106615D01*
G01X1090061Y98242D02*
Y95631D01*
G01D02*
G03X1090550Y94450I1670J0D01*
G01D02*
X1091750Y93250D01*
G01X1093861Y98242D02*
Y91239D01*
G01D02*
G03X1094250Y90300I1328J0D01*
G01X1090061Y106491D02*
G02X1090602Y107797I1847J0D01*
G01D02*
X1090707Y107902D01*
G01D02*
G03X1091286Y109300I-1398J1398D01*
G01D02*
Y124000D01*
G01X1093861Y106615D02*
G03X1093408Y107709I-1547J0D01*
G01D02*
X1093215Y107902D01*
G01D02*
G02X1092636Y109300I1398J1398D01*
G01D02*
Y124000D01*
G01X1091286D02*
G03X1090408Y126120I-2998J0D01*
G01D02*
X1090028Y126500D01*
G01X1092636Y124000D02*
G02X1093514Y126120I2998J0D01*
G01D02*
X1093894Y126500D01*
G01X1127696Y725355D02*
G02X1126063Y726032I1J2310D01*
G01D02*
X1124640Y727454D01*
G01D02*
G02X1124000Y729000I1547J1546D01*
G01X1124547Y725355D02*
G03X1124348Y725834I-678J-1D01*
G01D02*
X1124000Y726183D01*
G01D02*
X1121441Y728742D01*
G01D02*
X1120813Y729371D01*
G01D02*
G03X1120500Y729500I-312J-313D01*
G01X1181354Y267186D02*
X1163470Y285070D01*
G01D02*
G02X1160280Y292773I7703J7702D01*
G01X1182309Y268141D02*
X1164425Y286025D01*
G01D02*
G02X1161630Y292773I6748J6748D01*
G01X1160280D02*
Y311829D01*
G01X1161630Y292773D02*
Y311830D01*
G01X1160280Y311829D02*
G03X1159855Y312855I-1451J0D01*
G01D02*
X1159795Y312915D01*
G01D02*
G03X1157900Y313700I-1895J-1895D01*
G01D02*
G03X1156372Y313067I0J-2161D01*
G01D02*
X1156100Y312795D01*
G01X1161630Y311830D02*
G03X1160810Y313810I-2801J0D01*
G01D02*
X1160750Y313870D01*
G01D02*
G03X1157901Y315050I-2849J-2850D01*
G01D02*
G02X1157139Y315365I-1J1077D01*
G01D02*
X1156100Y316405D01*
G01X1185100Y265635D02*
G02X1181354Y267186I-1J5298D01*
G01X1185100Y266985D02*
G02X1182309Y268141I0J3947D01*
G01X1185493Y282993D02*
G03X1179801Y285350I-5691J-5692D01*
G01D02*
X1177499D01*
G01D02*
G02X1173335Y287075I2J5893D01*
G01X1184538Y282038D02*
G03X1179801Y284000I-4737J-4737D01*
G01D02*
X1177500D01*
G01D02*
G02X1172378Y286121I-1J7243D01*
G01D02*
X1172250Y286250D01*
G01D02*
X1170638Y287861D01*
G01X1173335Y287075D02*
X1172455Y287955D01*
G01D02*
G02Y288803I424J424D01*
G01D02*
X1173777Y290125D01*
G01X1170638Y287861D02*
G02X1169777Y289941I2081J2080D01*
G01D02*
Y290125D01*
G01X1209017Y301700D02*
X1175700D01*
G01D02*
G02X1170780Y306620I0J4920D01*
G01X1208414Y303050D02*
X1175700D01*
G01D02*
G02X1172130Y306620I0J3570D01*
G01D02*
Y321500D01*
G01X1170780Y306620D02*
Y321500D01*
G01X1172130D02*
G02X1172993Y323585I2948J1D01*
G01D02*
X1173125Y323716D01*
G01X1170780Y321500D02*
G03X1170108Y323124I-2296J1D01*
G01D02*
X1169515Y323716D01*
G01X1181240Y687560D02*
Y687578D01*
G01D02*
X1182817Y689155D01*
G01X1178090Y687560D02*
X1178127D01*
G01D02*
X1179678Y689111D01*
G01X1192418Y264060D02*
G03X1188616Y265635I-3802J-3802D01*
G01D02*
X1185100D01*
G01X1195918Y264060D02*
X1196682Y264823D01*
G01D02*
G02X1198677Y265650I1996J-1995D01*
G01D02*
X1199889D01*
G01D02*
G02X1200278Y265489I0J-550D01*
G01X1195918Y268560D02*
X1196630Y267848D01*
G01D02*
G03X1198677Y267000I2047J2047D01*
G01D02*
X1200346D01*
G01X1192418Y268560D02*
G02X1188616Y266985I-3802J3802D01*
G01D02*
X1185100D01*
G01X1209017Y277800D02*
X1192390D01*
G01D02*
G02X1189481Y279005I0J4114D01*
G01D02*
X1185493Y282993D01*
G01X1208914Y276450D02*
X1192389D01*
G01D02*
G02X1188526Y278050I0J5464D01*
G01D02*
X1184538Y282038D01*
G01X1197045Y286955D02*
G02X1195584Y286350I-1461J1461D01*
G01D02*
X1193569D01*
G01D02*
G02X1192000Y287000I0J2219D01*
G01X1200500Y288500D02*
X1198000Y286000D01*
G01D02*
G02X1195584Y285000I-2415J2416D01*
G01D02*
X1193568D01*
G01D02*
G02X1191045Y286045I0J3569D01*
G01D02*
X1190899Y286191D01*
G01D02*
G02X1190150Y288001I1808J1808D01*
G01X1202430Y290650D02*
G03X1199545Y289455I0J-4081D01*
G01D02*
X1197045Y286955D01*
G01X1192000Y287000D02*
X1191854Y287146D01*
G01D02*
G02X1191500Y288000I853J854D01*
G01D02*
G02X1191894Y288951I1345J0D01*
G01D02*
X1192743Y289800D01*
G01X1190150Y288001D02*
G03X1189778Y288899I-1270J0D01*
G01D02*
X1188877Y289800D01*
G01X1201565Y315965D02*
X1199765Y317765D01*
G01D02*
G02X1197150Y324081I6315J6314D01*
G01X1200720Y318720D02*
G02X1198500Y324080I5360J5360D01*
G01D02*
Y342600D01*
G01X1197150Y324081D02*
Y342600D01*
G01X1198500D02*
G02X1199068Y343971I1939J0D01*
G01D02*
X1199685Y344588D01*
G01X1197150Y342600D02*
G03X1196504Y344158I-2204J-1D01*
G01D02*
X1196075Y344588D01*
G01X1184389Y684410D02*
X1184496D01*
G01D02*
X1186107Y686021D01*
G01D02*
X1190827D01*
G01D02*
X1192937Y683911D01*
G01X1187539Y684410D02*
X1189533D01*
G01D02*
X1189890Y684053D01*
G01X1200278Y265489D02*
X1201246Y264521D01*
G01D02*
G03X1202766Y263892I1519J1520D01*
G01D02*
X1209554D01*
G01D02*
G02X1210500Y263500I0J-1338D01*
G01D02*
G03X1211724Y262993I1224J1224D01*
G01D02*
X1215256D01*
G01X1200346Y267000D02*
G02X1200911Y266766I0J-799D01*
G01D02*
X1202201Y265476D01*
G01D02*
G03X1202766Y265242I565J565D01*
G01D02*
X1209377D01*
G01D02*
G03X1210000Y265500I0J881D01*
G01D02*
X1210389Y265889D01*
G01D02*
G02X1211000Y266142I611J-611D01*
G01D02*
X1215256D01*
G01Y278741D02*
X1211000D01*
G01D02*
G03X1209705Y278205I0J-1832D01*
G01D02*
X1209500Y278000D01*
G01D02*
G02X1209017Y277800I-483J483D01*
G01X1215256Y275591D02*
X1210500D01*
G01D02*
G02X1210344Y275655I-1J220D01*
G01D02*
X1210000Y276000D01*
G01D02*
G03X1208914Y276450I-1086J-1086D01*
G01X1215256Y291339D02*
X1210318D01*
G01D02*
G03X1209500Y291000I0J-1157D01*
G01D02*
G02X1208655Y290650I-845J845D01*
G01D02*
X1202430D01*
G01X1215256Y288189D02*
X1210500D01*
G01D02*
G02X1210177Y288322I-1J456D01*
G01D02*
X1209500Y289000D01*
G01D02*
G03X1208776Y289300I-724J-724D01*
G01D02*
X1202431D01*
G01D02*
G03X1200500Y288500I0J-2731D01*
G01X1215256Y300788D02*
X1211000D01*
G01D02*
G02X1209655Y301345I0J1902D01*
G01D02*
X1209500Y301500D01*
G01D02*
G03X1209017Y301700I-483J-483D01*
G01X1215256Y303937D02*
X1210555D01*
G01D02*
G03X1209500Y303500I0J-1492D01*
G01D02*
G02X1208414Y303050I-1086J1086D01*
G01X1215256Y316536D02*
X1210500D01*
G01D02*
G03X1209708Y316208I0J-1120D01*
G01D02*
X1209500Y316000D01*
G01D02*
G02X1208534Y315600I-966J966D01*
G01D02*
X1205707D01*
G01D02*
G02X1202520Y316920I0J4507D01*
G01D02*
X1200720Y318720D01*
G01X1215256Y313386D02*
X1211482D01*
G01D02*
G02X1210000Y314000I0J2096D01*
G01D02*
G03X1209085Y314302I-757J-756D01*
G01D02*
X1208941Y314280D01*
G01D02*
G02X1208534Y314250I-403J2686D01*
G01D02*
X1205707D01*
G01D02*
G02X1201565Y315965I-1J5857D01*
G01X1237212Y269292D02*
X1232776D01*
G01Y285040D02*
X1237212D01*
G01X1232776Y281890D02*
X1237212D01*
G01Y272441D02*
X1232776D01*
G01Y297638D02*
X1237212D01*
G01X1232776Y294489D02*
X1237212D01*
G01X1232776Y310237D02*
X1237212D01*
G01X1232776Y307087D02*
X1237212D01*
G01X1232776Y322835D02*
X1237212D01*
G01X1232776Y319685D02*
X1237212D01*
G01X1247750Y268500D02*
X1249300D01*
G01X1244250D02*
X1242933Y269817D01*
G01D02*
G03X1242030Y270191I-903J-903D01*
G01X1238567D02*
G03X1238178Y270030I0J-550D01*
G01D02*
X1237601Y269453D01*
G01D02*
G02X1237212Y269292I-389J389D01*
G01Y285040D02*
G02X1237601Y284879I0J-550D01*
G01D02*
X1238179Y284301D01*
G01D02*
G03X1238568Y284140I389J389D01*
G01D02*
X1239263D01*
G01D02*
G03X1239720Y284330I-1J646D01*
G01D02*
X1239945Y284555D01*
G01D02*
G02X1243796Y286150I3851J-3852D01*
G01D02*
X1248600D01*
G01D02*
G03X1249841Y286664I0J1755D01*
G01X1237212Y281890D02*
G03X1237601Y282051I0J550D01*
G01D02*
X1238179Y282629D01*
G01D02*
G02X1238568Y282790I389J-389D01*
G01D02*
X1239263D01*
G01D02*
G03X1240675Y283375I0J1997D01*
G01D02*
X1240900Y283600D01*
G01D02*
G02X1243797Y284800I2897J-2897D01*
G01D02*
X1248600D01*
G01D02*
G02X1249927Y284251I1J-1876D01*
G01X1247750Y272500D02*
X1249300D01*
G01X1244250D02*
G02X1241935Y271541I-2315J2315D01*
G01D02*
X1238568D01*
G01D02*
G02X1238179Y271702I0J550D01*
G01D02*
X1237601Y272280D01*
G01D02*
G03X1237212Y272441I-389J-389D01*
G01X1242030Y270191D02*
X1238567D01*
G01X1237212Y297638D02*
G02X1237601Y297477I0J-550D01*
G01D02*
X1238178Y296900D01*
G01D02*
G03X1238567Y296739I389J389D01*
G01D02*
X1244742D01*
G01D02*
G03X1245745Y297155I-1J1419D01*
G01D02*
G02X1249113Y298550I3368J-3369D01*
G01D02*
X1258700D01*
G01X1237212Y294489D02*
G03X1237601Y294650I0J550D01*
G01D02*
X1238179Y295228D01*
G01D02*
G02X1238568Y295389I389J-389D01*
G01D02*
X1244742D01*
G01D02*
G03X1246700Y296200I0J2769D01*
G01D02*
G02X1249114Y297200I2414J-2414D01*
G01D02*
X1258700D01*
G01X1237212Y310237D02*
G02X1237601Y310076I0J-550D01*
G01D02*
X1238179Y309498D01*
G01D02*
G03X1238568Y309337I389J389D01*
G01D02*
X1243124D01*
G01D02*
G03X1244000Y309700I0J1239D01*
G01D02*
G02X1247380Y311100I3380J-3380D01*
G01D02*
X1251400D01*
G01X1237212Y307087D02*
G03X1237601Y307248I0J550D01*
G01D02*
X1238179Y307826D01*
G01D02*
G02X1238568Y307987I389J-389D01*
G01D02*
X1243125D01*
G01D02*
G03X1244955Y308745I0J2589D01*
G01D02*
G02X1247379Y309750I2426J-2425D01*
G01D02*
X1251400D01*
G01X1237212Y322835D02*
G02X1237601Y322674I0J-550D01*
G01D02*
X1238179Y322096D01*
G01D02*
G03X1238568Y321935I389J389D01*
G01D02*
X1241636D01*
G01D02*
G03X1243000Y322500I0J1929D01*
G01D02*
G02X1244207Y323000I1207J-1207D01*
G01D02*
X1251000D01*
G01X1237212Y319685D02*
G03X1237601Y319846I0J550D01*
G01D02*
X1238179Y320424D01*
G01D02*
G02X1238568Y320585I389J-389D01*
G01D02*
X1241637D01*
G01D02*
G03X1243955Y321545I0J3279D01*
G01D02*
G02X1244208Y321650I253J-252D01*
G01D02*
X1251000D01*
G01X1249300Y268500D02*
G03X1249850Y269050I0J550D01*
G01D02*
Y269275D01*
G01D02*
G02X1250400Y269825I550J0D01*
G01D02*
X1253458D01*
G01D02*
G02X1253847Y269664I0J-550D01*
G01D02*
X1254944Y268567D01*
G01X1249841Y286664D02*
X1250677Y287500D01*
G01X1249927Y284251D02*
X1250677Y283500D01*
G01X1249300Y272500D02*
G02X1249850Y271950I0J-550D01*
G01D02*
Y271725D01*
G01D02*
G03X1250400Y271175I550J0D01*
G01D02*
X1253458D01*
G01D02*
G03X1253847Y271336I0J550D01*
G01D02*
X1254944Y272433D01*
G01X1258700Y298550D02*
G03X1259483Y298875I-1J1108D01*
G01D02*
X1260577Y299968D01*
G01X1258700Y297200D02*
G02X1260030Y296649I0J-1881D01*
G01D02*
X1260577Y296102D01*
G01X1251400Y311100D02*
G03X1252043Y311367I-1J910D01*
G01D02*
X1253477Y312800D01*
G01X1251400Y309750D02*
G02X1253494Y308882I-1J-2962D01*
G01D02*
X1253577Y308800D01*
G01X1251000Y323000D02*
G03X1252155Y323479I-1J1634D01*
G01D02*
X1253177Y324500D01*
G01X1251000Y321650D02*
G02X1252753Y320924I0J-2479D01*
G01D02*
X1253177Y320500D01*
G01X1329650Y540815D02*
Y532000D01*
G01D02*
G02X1327200Y529550I-2450J0D01*
G01D02*
X1323345D01*
G01D02*
G02X1322500Y529900I0J1195D01*
G01D02*
G02X1322400Y530141I241J241D01*
G01D02*
Y533100D01*
G01X1322900Y524600D02*
Y526422D01*
G01D02*
G02X1323450Y527750I1878J0D01*
G01D02*
G02X1323926Y528073I1085J-1087D01*
G01D02*
G02X1324536Y528200I612J-1409D01*
G01D02*
X1327200D01*
G01D02*
G03X1331000Y532000I0J3800D01*
G01D02*
Y560000D01*
G01X1328860Y550505D02*
Y548855D01*
G01D02*
G03X1329255Y548065I990J1D01*
G01D02*
G02X1329650Y547275I-595J-791D01*
G01D02*
Y545625D01*
G01D02*
G02X1329255Y544835I-990J1D01*
G01D02*
G03X1328860Y544045I595J-791D01*
G01D02*
Y542395D01*
G01D02*
G03X1329255Y541605I990J1D01*
G01D02*
G02X1329650Y540815I-595J-791D01*
G01X1333083Y568288D02*
G03X1329650Y560000I8288J-8288D01*
G01D02*
Y552085D01*
G01D02*
G02X1329255Y551295I-990J1D01*
G01D02*
G03X1328860Y550505I595J-791D01*
G01X1331000Y560000D02*
G02X1334038Y567333I10371J-1D01*
G01X1340680Y582112D02*
Y577749D01*
G01D02*
G02X1339362Y574567I-4500J0D01*
G01D02*
X1333083Y568288D01*
G01X1334038Y567333D02*
X1340317Y573612D01*
G01D02*
G03X1342648Y579240I-5628J5628D01*
G01D02*
Y582112D01*
G01X1368500Y529950D02*
X1353469D01*
G01D02*
G02X1351900Y530600I0J2219D01*
G01D02*
G02Y533100I1250J1250D01*
G01X1368500Y528600D02*
X1355031D01*
G01D02*
G03X1354946Y528598I16J-2489D01*
G01D02*
G03X1353271Y527871I84J-2487D01*
G01D02*
X1352450Y527050D01*
G01D02*
G03X1351900Y525722I1328J-1328D01*
G01D02*
Y524600D01*
G01Y533100D02*
X1352400Y533600D01*
G01X1361582Y582777D02*
G03X1361861Y581939I981J-139D01*
G01D02*
X1363028Y580773D01*
G01D02*
G03X1363866Y580494I699J701D01*
G01D02*
G02X1364704Y580214I138J-980D01*
G01X1356267Y585538D02*
X1358311D01*
G01D02*
G02X1360136Y584782I0J-2581D01*
G01D02*
X1361303Y583615D01*
G01D02*
G02X1361582Y582777I-701J-699D01*
G01X1355917Y587506D02*
X1356644D01*
G01D02*
G02X1361217Y585612I0J-6467D01*
G01D02*
X1375914Y570915D01*
G01X1364717Y587286D02*
G02X1361348Y588681I-1J4764D01*
G01D02*
G03X1359431Y589475I-1917J-1917D01*
G01D02*
X1355917D01*
G01X1364717Y588636D02*
G02X1362303Y589636I0J3414D01*
G01D02*
X1362022Y589917D01*
G01D02*
G03X1358338Y591443I-3684J-3684D01*
G01D02*
X1355917D01*
G01X1364194Y598535D02*
X1362844Y597185D01*
G01D02*
X1361764Y596104D01*
G01D02*
G02X1360017Y595381I-1746J1747D01*
G01D02*
X1355917D01*
G01X1363239Y599490D02*
X1362188Y598440D01*
G01D02*
G02X1359554Y597349I-2634J2634D01*
G01D02*
X1355917D01*
G01X1365347Y600362D02*
G03X1363239Y599490I-2J-2979D01*
G01X1367766Y607401D02*
X1362057Y601692D01*
G01D02*
X1362046Y601687D01*
G01D02*
X1362022Y601677D01*
G01D02*
G02X1356327Y599318I-5695J5695D01*
G01D02*
X1355917D01*
G01X1369867Y611412D02*
X1361292Y602837D01*
G01D02*
G02X1357548Y601286I-3744J3744D01*
G01D02*
X1356267D01*
G01X1374000Y533500D02*
X1371829Y531329D01*
G01D02*
G02X1368500Y529950I-3329J3329D01*
G01X1377850Y539536D02*
G02X1374955Y532545I-9886J-1D01*
G01D02*
X1372784Y530374D01*
G01D02*
G02X1368500Y528600I-4283J4284D01*
G01X1375710Y549226D02*
G03X1376105Y548436I990J1D01*
G01D02*
G02X1376500Y547646I-595J-791D01*
G01D02*
Y545996D01*
G01D02*
G02X1376105Y545206I-990J1D01*
G01D02*
G03X1375710Y544416I595J-791D01*
G01D02*
Y542766D01*
G01D02*
G03X1376105Y541976I990J1D01*
G01D02*
G02X1376500Y541186I-595J-791D01*
G01D02*
Y539536D01*
G01D02*
G02X1374000Y533500I-8536J0D01*
G01X1377850Y566241D02*
Y539536D01*
G01X1376500Y566240D02*
Y558916D01*
G01D02*
G02X1376105Y558126I-990J1D01*
G01D02*
G03X1375710Y557336I595J-791D01*
G01D02*
Y555686D01*
G01D02*
G03X1376105Y554896I990J1D01*
G01D02*
G02X1376500Y554106I-595J-791D01*
G01D02*
Y552456D01*
G01D02*
G02X1376105Y551666I-990J1D01*
G01D02*
G03X1375710Y550876I595J-791D01*
G01D02*
Y549226D01*
G01X1364704Y580214D02*
X1365871Y579048D01*
G01D02*
G02X1366150Y578210I-701J-699D01*
G01D02*
G03X1366430Y577372I980J-138D01*
G01D02*
X1367596Y576205D01*
G01D02*
G03X1368434Y575926I699J701D01*
G01D02*
G02X1369272Y575646I138J-980D01*
G01D02*
X1370439Y574480D01*
G01D02*
G02X1370718Y573642I-701J-699D01*
G01D02*
G03X1370998Y572804I980J-138D01*
G01D02*
X1372164Y571637D01*
G01D02*
G03X1373002Y571358I699J701D01*
G01D02*
G02X1373840Y571079I139J-980D01*
G01D02*
X1374959Y569960D01*
G01D02*
G02X1376500Y566240I-3720J-3720D01*
G01X1375914Y570915D02*
G02X1377850Y566241I-4675J-4674D01*
G01X1373367Y585412D02*
X1374162D01*
G01D02*
X1375700Y586950D01*
G01D02*
X1381050D01*
G01X1373367Y589912D02*
X1374088D01*
G01D02*
X1375700Y588300D01*
G01D02*
X1381610D01*
G01X1369867Y585412D02*
X1368754Y586525D01*
G01D02*
G03X1366917Y587286I-1837J-1837D01*
G01D02*
X1364717D01*
G01X1369867Y589912D02*
X1369421Y589466D01*
G01D02*
G02X1367417Y588636I-2004J2004D01*
G01D02*
X1364717D01*
G01X1369867Y597912D02*
G03X1367211Y599012I-2656J-2656D01*
G01X1373367Y597912D02*
X1374955Y599500D01*
G01X1373367Y606912D02*
X1374895Y608440D01*
G01D02*
X1376938D01*
G01D02*
X1377996Y607382D01*
G01X1373367Y611412D02*
X1374989Y609790D01*
G01D02*
X1376939D01*
G01D02*
X1377996Y610847D01*
G01X1367211Y599012D02*
X1365346D01*
G01D02*
G03X1364194Y598535I0J-1629D01*
G01X1369867Y602412D02*
X1368245Y600791D01*
G01D02*
G02X1367211Y600362I-1035J1034D01*
G01D02*
X1365347D01*
G01X1369867Y606912D02*
G03X1369067Y607712I-800J0D01*
G01D02*
X1368517D01*
G01D02*
G03X1367766Y607401I0J-1062D01*
G01X1374955Y599500D02*
X1379740D01*
G01D02*
X1380925Y598315D01*
G01X1373367Y602412D02*
X1374929Y600850D01*
G01D02*
X1379740D01*
G01D02*
X1380925Y602035D01*
G01X1382600Y582380D02*
X1381415Y581195D01*
G01X1383950Y582380D02*
X1385135Y581195D01*
G01X1381050Y586950D02*
X1382600Y585400D01*
G01D02*
Y582380D01*
G01X1381610Y588300D02*
X1383950Y585960D01*
G01D02*
Y582380D01*
M02*
